(kicad_sch
	(version 20231120)
	(generator "eeschema")
	(generator_version "8.0")
	(paper "A3")
	(title_block
		(title "Jetson Orin Baseboard")
		(date "2025-03-12")
		(rev "1.3.4")
		(company "Antmicro Ltd")
		(comment 1 "www.antmicro.com")
	)
	(junction
		(at 68.58 57.15)
		(diameter 0)
		(color 0 0 0 0)
	)
	(junction
		(at 110.49 163.83)
		(diameter 0)
		(color 0 0 0 0)
	)
	(junction
		(at 105.41 163.83)
		(diameter 0)
		(color 0 0 0 0)
	)
	(junction
		(at 46.99 109.22)
		(diameter 0)
		(color 0 0 0 0)
	)
	(junction
		(at 38.1 109.22)
		(diameter 0)
		(color 0 0 0 0)
	)
	(junction
		(at 113.03 176.53)
		(diameter 0)
		(color 0 0 0 0)
	)
	(junction
		(at 115.57 49.53)
		(diameter 0)
		(color 0 0 0 0)
	)
	(junction
		(at 41.91 146.05)
		(diameter 0)
		(color 0 0 0 0)
	)
	(junction
		(at 71.12 54.61)
		(diameter 0)
		(color 0 0 0 0)
	)
	(junction
		(at 151.13 273.05)
		(diameter 0)
		(color 0 0 0 0)
	)
	(junction
		(at 113.03 163.83)
		(diameter 0)
		(color 0 0 0 0)
	)
	(junction
		(at 91.44 236.22)
		(diameter 0)
		(color 0 0 0 0)
	)
	(junction
		(at 60.96 236.22)
		(diameter 0)
		(color 0 0 0 0)
	)
	(junction
		(at 64.77 250.19)
		(diameter 0)
		(color 0 0 0 0)
	)
	(no_connect
		(at 195.58 52.07)
	)
	(no_connect
		(at 195.58 54.61)
	)
	(no_connect
		(at 55.88 158.75)
	)
	(no_connect
		(at 55.88 156.21)
	)
	(no_connect
		(at 278.13 234.95)
	)
	(no_connect
		(at 278.13 229.87)
	)
	(no_connect
		(at 278.13 232.41)
	)
	(no_connect
		(at 276.86 142.24)
	)
	(no_connect
		(at 276.86 129.54)
	)
	(no_connect
		(at 276.86 132.08)
	)
	(no_connect
		(at 276.86 134.62)
	)
	(no_connect
		(at 276.86 137.16)
	)
	(no_connect
		(at 276.86 139.7)
	)
	(wire
		(pts
			(xy 365.76 137.16) (xy 375.92 137.16)
		)
		(stroke
			(width 0)
			(type default)
		)
	)
	(wire
		(pts
			(xy 64.77 49.53) (xy 115.57 49.53)
		)
		(stroke
			(width 0)
			(type default)
		)
	)
	(wire
		(pts
			(xy 278.13 100.33) (xy 276.86 100.33)
		)
		(stroke
			(width 0)
			(type default)
		)
	)
	(wire
		(pts
			(xy 68.58 63.5) (xy 68.58 57.15)
		)
		(stroke
			(width 0)
			(type default)
		)
	)
	(wire
		(pts
			(xy 189.23 228.6) (xy 194.31 228.6)
		)
		(stroke
			(width 0)
			(type default)
		)
	)
	(wire
		(pts
			(xy 87.63 250.19) (xy 86.36 250.19)
		)
		(stroke
			(width 0)
			(type default)
		)
	)
	(wire
		(pts
			(xy 375.92 127) (xy 365.76 127)
		)
		(stroke
			(width 0)
			(type default)
		)
	)
	(wire
		(pts
			(xy 54.61 109.22) (xy 54.61 135.89)
		)
		(stroke
			(width 0)
			(type default)
		)
	)
	(wire
		(pts
			(xy 193.04 143.51) (xy 194.31 143.51)
		)
		(stroke
			(width 0)
			(type default)
		)
	)
	(wire
		(pts
			(xy 193.04 130.81) (xy 194.31 130.81)
		)
		(stroke
			(width 0)
			(type default)
		)
	)
	(wire
		(pts
			(xy 194.31 97.79) (xy 193.04 97.79)
		)
		(stroke
			(width 0)
			(type default)
		)
	)
	(wire
		(pts
			(xy 189.23 219.71) (xy 194.31 219.71)
		)
		(stroke
			(width 0)
			(type default)
		)
	)
	(wire
		(pts
			(xy 278.13 76.2) (xy 276.86 76.2)
		)
		(stroke
			(width 0)
			(type default)
		)
	)
	(wire
		(pts
			(xy 24.13 109.22) (xy 24.13 106.68)
		)
		(stroke
			(width 0)
			(type default)
		)
	)
	(wire
		(pts
			(xy 377.19 240.03) (xy 367.03 240.03)
		)
		(stroke
			(width 0)
			(type default)
		)
	)
	(wire
		(pts
			(xy 194.31 74.93) (xy 193.04 74.93)
		)
		(stroke
			(width 0)
			(type default)
		)
	)
	(wire
		(pts
			(xy 194.31 140.97) (xy 193.04 140.97)
		)
		(stroke
			(width 0)
			(type default)
		)
	)
	(wire
		(pts
			(xy 377.19 229.87) (xy 367.03 229.87)
		)
		(stroke
			(width 0)
			(type default)
		)
	)
	(wire
		(pts
			(xy 151.13 273.05) (xy 151.13 276.86)
		)
		(stroke
			(width 0)
			(type default)
		)
	)
	(wire
		(pts
			(xy 91.44 234.95) (xy 91.44 236.22)
		)
		(stroke
			(width 0)
			(type default)
		)
	)
	(wire
		(pts
			(xy 189.23 246.38) (xy 194.31 246.38)
		)
		(stroke
			(width 0)
			(type default)
		)
	)
	(wire
		(pts
			(xy 113.03 175.26) (xy 113.03 176.53)
		)
		(stroke
			(width 0)
			(type default)
		)
	)
	(wire
		(pts
			(xy 377.19 236.22) (xy 367.03 236.22)
		)
		(stroke
			(width 0)
			(type default)
		)
	)
	(wire
		(pts
			(xy 194.31 128.27) (xy 193.04 128.27)
		)
		(stroke
			(width 0)
			(type default)
		)
	)
	(wire
		(pts
			(xy 68.58 57.15) (xy 64.77 57.15)
		)
		(stroke
			(width 0)
			(type default)
		)
	)
	(wire
		(pts
			(xy 113.03 163.83) (xy 130.81 163.83)
		)
		(stroke
			(width 0)
			(type default)
		)
	)
	(wire
		(pts
			(xy 278.13 73.66) (xy 276.86 73.66)
		)
		(stroke
			(width 0)
			(type default)
		)
	)
	(wire
		(pts
			(xy 115.57 46.99) (xy 115.57 49.53)
		)
		(stroke
			(width 0)
			(type default)
		)
	)
	(wire
		(pts
			(xy 64.77 250.19) (xy 64.77 257.81)
		)
		(stroke
			(width 0)
			(type default)
		)
	)
	(wire
		(pts
			(xy 194.31 118.11) (xy 193.04 118.11)
		)
		(stroke
			(width 0)
			(type default)
		)
	)
	(wire
		(pts
			(xy 278.13 55.88) (xy 276.86 55.88)
		)
		(stroke
			(width 0)
			(type default)
		)
	)
	(wire
		(pts
			(xy 365.76 68.58) (xy 375.92 68.58)
		)
		(stroke
			(width 0)
			(type default)
		)
	)
	(wire
		(pts
			(xy 45.72 252.73) (xy 66.04 252.73)
		)
		(stroke
			(width 0)
			(type default)
		)
	)
	(wire
		(pts
			(xy 278.13 191.77) (xy 283.21 191.77)
		)
		(stroke
			(width 0)
			(type default)
		)
	)
	(wire
		(pts
			(xy 60.96 236.22) (xy 60.96 237.49)
		)
		(stroke
			(width 0)
			(type default)
		)
	)
	(wire
		(pts
			(xy 105.41 172.72) (xy 105.41 177.8)
		)
		(stroke
			(width 0)
			(type default)
		)
	)
	(wire
		(pts
			(xy 189.23 186.69) (xy 194.31 186.69)
		)
		(stroke
			(width 0)
			(type default)
		)
	)
	(wire
		(pts
			(xy 365.76 66.04) (xy 375.92 66.04)
		)
		(stroke
			(width 0)
			(type default)
		)
	)
	(wire
		(pts
			(xy 104.14 149.86) (xy 110.49 149.86)
		)
		(stroke
			(width 0)
			(type default)
		)
	)
	(wire
		(pts
			(xy 365.76 106.68) (xy 375.92 106.68)
		)
		(stroke
			(width 0)
			(type default)
		)
	)
	(polyline
		(pts
			(xy 12.7 218.44) (xy 139.7 218.44)
		)
		(stroke
			(width 0)
			(type default)
		)
	)
	(wire
		(pts
			(xy 365.76 109.22) (xy 375.92 109.22)
		)
		(stroke
			(width 0)
			(type default)
		)
	)
	(wire
		(pts
			(xy 194.31 120.65) (xy 193.04 120.65)
		)
		(stroke
			(width 0)
			(type default)
		)
	)
	(wire
		(pts
			(xy 375.92 157.48) (xy 365.76 157.48)
		)
		(stroke
			(width 0)
			(type default)
		)
	)
	(wire
		(pts
			(xy 60.96 236.22) (xy 64.77 236.22)
		)
		(stroke
			(width 0)
			(type default)
		)
	)
	(wire
		(pts
			(xy 278.13 58.42) (xy 276.86 58.42)
		)
		(stroke
			(width 0)
			(type default)
		)
	)
	(wire
		(pts
			(xy 194.31 95.25) (xy 193.04 95.25)
		)
		(stroke
			(width 0)
			(type default)
		)
	)
	(wire
		(pts
			(xy 278.13 124.46) (xy 276.86 124.46)
		)
		(stroke
			(width 0)
			(type default)
		)
	)
	(wire
		(pts
			(xy 365.76 168.91) (xy 375.92 168.91)
		)
		(stroke
			(width 0)
			(type default)
		)
	)
	(wire
		(pts
			(xy 194.31 88.9) (xy 193.04 88.9)
		)
		(stroke
			(width 0)
			(type default)
		)
	)
	(wire
		(pts
			(xy 194.31 110.49) (xy 193.04 110.49)
		)
		(stroke
			(width 0)
			(type default)
		)
	)
	(wire
		(pts
			(xy 194.31 82.55) (xy 193.04 82.55)
		)
		(stroke
			(width 0)
			(type default)
		)
	)
	(wire
		(pts
			(xy 38.1 109.22) (xy 46.99 109.22)
		)
		(stroke
			(width 0)
			(type default)
		)
	)
	(wire
		(pts
			(xy 66.04 250.19) (xy 64.77 250.19)
		)
		(stroke
			(width 0)
			(type default)
		)
	)
	(wire
		(pts
			(xy 91.44 34.29) (xy 64.77 34.29)
		)
		(stroke
			(width 0)
			(type default)
		)
	)
	(wire
		(pts
			(xy 41.91 162.56) (xy 41.91 165.1)
		)
		(stroke
			(width 0)
			(type default)
		)
	)
	(wire
		(pts
			(xy 189.23 208.28) (xy 194.31 208.28)
		)
		(stroke
			(width 0)
			(type default)
		)
	)
	(wire
		(pts
			(xy 193.04 67.31) (xy 215.9 67.31)
		)
		(stroke
			(width 0)
			(type default)
		)
	)
	(wire
		(pts
			(xy 365.76 120.65) (xy 375.92 120.65)
		)
		(stroke
			(width 0)
			(type default)
		)
	)
	(wire
		(pts
			(xy 278.13 83.82) (xy 276.86 83.82)
		)
		(stroke
			(width 0)
			(type default)
		)
	)
	(wire
		(pts
			(xy 110.49 176.53) (xy 110.49 175.26)
		)
		(stroke
			(width 0)
			(type default)
		)
	)
	(wire
		(pts
			(xy 189.23 233.68) (xy 194.31 233.68)
		)
		(stroke
			(width 0)
			(type default)
		)
	)
	(wire
		(pts
			(xy 375.92 44.45) (xy 365.76 44.45)
		)
		(stroke
			(width 0)
			(type default)
		)
	)
	(wire
		(pts
			(xy 104.14 139.7) (xy 110.49 139.7)
		)
		(stroke
			(width 0)
			(type default)
		)
	)
	(wire
		(pts
			(xy 55.88 142.24) (xy 41.91 142.24)
		)
		(stroke
			(width 0)
			(type default)
		)
	)
	(wire
		(pts
			(xy 64.77 257.81) (xy 66.04 257.81)
		)
		(stroke
			(width 0)
			(type default)
		)
	)
	(wire
		(pts
			(xy 194.31 105.41) (xy 193.04 105.41)
		)
		(stroke
			(width 0)
			(type default)
		)
	)
	(wire
		(pts
			(xy 194.31 86.36) (xy 193.04 86.36)
		)
		(stroke
			(width 0)
			(type default)
		)
	)
	(wire
		(pts
			(xy 189.23 240.03) (xy 194.31 240.03)
		)
		(stroke
			(width 0)
			(type default)
		)
	)
	(wire
		(pts
			(xy 24.13 109.22) (xy 29.21 109.22)
		)
		(stroke
			(width 0)
			(type default)
		)
	)
	(wire
		(pts
			(xy 64.77 236.22) (xy 64.77 250.19)
		)
		(stroke
			(width 0)
			(type default)
		)
	)
	(wire
		(pts
			(xy 91.44 44.45) (xy 64.77 44.45)
		)
		(stroke
			(width 0)
			(type default)
		)
	)
	(wire
		(pts
			(xy 87.63 257.81) (xy 87.63 259.08)
		)
		(stroke
			(width 0)
			(type default)
		)
	)
	(wire
		(pts
			(xy 375.92 151.13) (xy 365.76 151.13)
		)
		(stroke
			(width 0)
			(type default)
		)
	)
	(wire
		(pts
			(xy 86.36 257.81) (xy 87.63 257.81)
		)
		(stroke
			(width 0)
			(type default)
		)
	)
	(wire
		(pts
			(xy 193.04 64.77) (xy 215.9 64.77)
		)
		(stroke
			(width 0)
			(type default)
		)
	)
	(wire
		(pts
			(xy 151.13 266.7) (xy 151.13 273.05)
		)
		(stroke
			(width 0)
			(type default)
		)
	)
	(wire
		(pts
			(xy 375.92 91.44) (xy 365.76 91.44)
		)
		(stroke
			(width 0)
			(type default)
		)
	)
	(wire
		(pts
			(xy 278.13 209.55) (xy 283.21 209.55)
		)
		(stroke
			(width 0)
			(type default)
		)
	)
	(wire
		(pts
			(xy 375.92 85.09) (xy 365.76 85.09)
		)
		(stroke
			(width 0)
			(type default)
		)
	)
	(wire
		(pts
			(xy 377.19 227.33) (xy 367.03 227.33)
		)
		(stroke
			(width 0)
			(type default)
		)
	)
	(wire
		(pts
			(xy 278.13 92.71) (xy 276.86 92.71)
		)
		(stroke
			(width 0)
			(type default)
		)
	)
	(polyline
		(pts
			(xy 139.7 165.1) (xy 228.6 165.1)
		)
		(stroke
			(width 0)
			(type default)
		)
	)
	(wire
		(pts
			(xy 189.23 200.66) (xy 194.31 200.66)
		)
		(stroke
			(width 0)
			(type default)
		)
	)
	(wire
		(pts
			(xy 278.13 48.26) (xy 276.86 48.26)
		)
		(stroke
			(width 0)
			(type default)
		)
	)
	(wire
		(pts
			(xy 105.41 163.83) (xy 105.41 167.64)
		)
		(stroke
			(width 0)
			(type default)
		)
	)
	(wire
		(pts
			(xy 152.4 266.7) (xy 151.13 266.7)
		)
		(stroke
			(width 0)
			(type default)
		)
	)
	(wire
		(pts
			(xy 365.76 130.81) (xy 375.92 130.81)
		)
		(stroke
			(width 0)
			(type default)
		)
	)
	(wire
		(pts
			(xy 104.14 163.83) (xy 105.41 163.83)
		)
		(stroke
			(width 0)
			(type default)
		)
	)
	(wire
		(pts
			(xy 194.31 125.73) (xy 193.04 125.73)
		)
		(stroke
			(width 0)
			(type default)
		)
	)
	(wire
		(pts
			(xy 41.91 142.24) (xy 41.91 146.05)
		)
		(stroke
			(width 0)
			(type default)
		)
	)
	(wire
		(pts
			(xy 278.13 205.74) (xy 283.21 205.74)
		)
		(stroke
			(width 0)
			(type default)
		)
	)
	(wire
		(pts
			(xy 71.12 60.96) (xy 71.12 54.61)
		)
		(stroke
			(width 0)
			(type default)
		)
	)
	(wire
		(pts
			(xy 375.92 80.01) (xy 365.76 80.01)
		)
		(stroke
			(width 0)
			(type default)
		)
	)
	(wire
		(pts
			(xy 41.91 146.05) (xy 41.91 147.32)
		)
		(stroke
			(width 0)
			(type default)
		)
	)
	(wire
		(pts
			(xy 74.93 54.61) (xy 71.12 54.61)
		)
		(stroke
			(width 0)
			(type default)
		)
	)
	(wire
		(pts
			(xy 54.61 163.83) (xy 55.88 163.83)
		)
		(stroke
			(width 0)
			(type default)
		)
	)
	(wire
		(pts
			(xy 278.13 224.79) (xy 283.21 224.79)
		)
		(stroke
			(width 0)
			(type default)
		)
	)
	(wire
		(pts
			(xy 195.58 52.07) (xy 193.04 52.07)
		)
		(stroke
			(width 0)
			(type default)
		)
	)
	(wire
		(pts
			(xy 74.93 57.15) (xy 68.58 57.15)
		)
		(stroke
			(width 0)
			(type default)
		)
	)
	(wire
		(pts
			(xy 278.13 60.96) (xy 276.86 60.96)
		)
		(stroke
			(width 0)
			(type default)
		)
	)
	(wire
		(pts
			(xy 377.19 220.98) (xy 367.03 220.98)
		)
		(stroke
			(width 0)
			(type default)
		)
	)
	(wire
		(pts
			(xy 194.31 80.01) (xy 193.04 80.01)
		)
		(stroke
			(width 0)
			(type default)
		)
	)
	(wire
		(pts
			(xy 80.01 63.5) (xy 91.44 63.5)
		)
		(stroke
			(width 0)
			(type default)
		)
	)
	(wire
		(pts
			(xy 88.9 255.27) (xy 86.36 255.27)
		)
		(stroke
			(width 0)
			(type default)
		)
	)
	(wire
		(pts
			(xy 278.13 81.28) (xy 276.86 81.28)
		)
		(stroke
			(width 0)
			(type default)
		)
	)
	(wire
		(pts
			(xy 104.14 137.16) (xy 110.49 137.16)
		)
		(stroke
			(width 0)
			(type default)
		)
	)
	(wire
		(pts
			(xy 377.19 223.52) (xy 367.03 223.52)
		)
		(stroke
			(width 0)
			(type default)
		)
	)
	(wire
		(pts
			(xy 16.51 146.05) (xy 26.67 146.05)
		)
		(stroke
			(width 0)
			(type default)
		)
	)
	(polyline
		(pts
			(xy 12.7 67.31) (xy 139.7 67.31)
		)
		(stroke
			(width 0)
			(type default)
		)
	)
	(polyline
		(pts
			(xy 317.5 190.5) (xy 406.4 190.5)
		)
		(stroke
			(width 0)
			(type default)
		)
	)
	(wire
		(pts
			(xy 278.13 218.44) (xy 283.21 218.44)
		)
		(stroke
			(width 0)
			(type default)
		)
	)
	(wire
		(pts
			(xy 278.13 196.85) (xy 283.21 196.85)
		)
		(stroke
			(width 0)
			(type default)
		)
	)
	(wire
		(pts
			(xy 278.13 212.09) (xy 283.21 212.09)
		)
		(stroke
			(width 0)
			(type default)
		)
	)
	(wire
		(pts
			(xy 377.19 233.68) (xy 367.03 233.68)
		)
		(stroke
			(width 0)
			(type default)
		)
	)
	(wire
		(pts
			(xy 365.76 62.23) (xy 375.92 62.23)
		)
		(stroke
			(width 0)
			(type default)
		)
	)
	(wire
		(pts
			(xy 74.93 60.96) (xy 71.12 60.96)
		)
		(stroke
			(width 0)
			(type default)
		)
	)
	(wire
		(pts
			(xy 365.76 38.1) (xy 375.92 38.1)
		)
		(stroke
			(width 0)
			(type default)
		)
	)
	(wire
		(pts
			(xy 281.94 111.76) (xy 276.86 111.76)
		)
		(stroke
			(width 0)
			(type default)
		)
	)
	(polyline
		(pts
			(xy 139.7 13.97) (xy 139.7 283.21)
		)
		(stroke
			(width 0)
			(type default)
		)
	)
	(wire
		(pts
			(xy 365.76 144.78) (xy 375.92 144.78)
		)
		(stroke
			(width 0)
			(type default)
		)
	)
	(wire
		(pts
			(xy 189.23 212.09) (xy 194.31 212.09)
		)
		(stroke
			(width 0)
			(type default)
		)
	)
	(wire
		(pts
			(xy 195.58 39.37) (xy 193.04 39.37)
		)
		(stroke
			(width 0)
			(type default)
		)
	)
	(wire
		(pts
			(xy 189.23 236.22) (xy 194.31 236.22)
		)
		(stroke
			(width 0)
			(type default)
		)
	)
	(wire
		(pts
			(xy 87.63 236.22) (xy 87.63 250.19)
		)
		(stroke
			(width 0)
			(type default)
		)
	)
	(wire
		(pts
			(xy 278.13 102.87) (xy 276.86 102.87)
		)
		(stroke
			(width 0)
			(type default)
		)
	)
	(wire
		(pts
			(xy 287.02 111.76) (xy 295.91 111.76)
		)
		(stroke
			(width 0)
			(type default)
		)
	)
	(wire
		(pts
			(xy 110.49 163.83) (xy 113.03 163.83)
		)
		(stroke
			(width 0)
			(type default)
		)
	)
	(wire
		(pts
			(xy 80.01 57.15) (xy 91.44 57.15)
		)
		(stroke
			(width 0)
			(type default)
		)
	)
	(wire
		(pts
			(xy 365.76 71.12) (xy 375.92 71.12)
		)
		(stroke
			(width 0)
			(type default)
		)
	)
	(wire
		(pts
			(xy 104.14 133.35) (xy 110.49 133.35)
		)
		(stroke
			(width 0)
			(type default)
		)
	)
	(wire
		(pts
			(xy 375.92 82.55) (xy 365.76 82.55)
		)
		(stroke
			(width 0)
			(type default)
		)
	)
	(wire
		(pts
			(xy 193.04 146.05) (xy 194.31 146.05)
		)
		(stroke
			(width 0)
			(type default)
		)
	)
	(wire
		(pts
			(xy 377.19 215.9) (xy 367.03 215.9)
		)
		(stroke
			(width 0)
			(type default)
		)
	)
	(wire
		(pts
			(xy 189.23 226.06) (xy 194.31 226.06)
		)
		(stroke
			(width 0)
			(type default)
		)
	)
	(wire
		(pts
			(xy 375.92 124.46) (xy 365.76 124.46)
		)
		(stroke
			(width 0)
			(type default)
		)
	)
	(polyline
		(pts
			(xy 228.6 13.97) (xy 228.6 283.21)
		)
		(stroke
			(width 0)
			(type default)
		)
	)
	(wire
		(pts
			(xy 194.31 100.33) (xy 193.04 100.33)
		)
		(stroke
			(width 0)
			(type default)
		)
	)
	(wire
		(pts
			(xy 278.13 63.5) (xy 276.86 63.5)
		)
		(stroke
			(width 0)
			(type default)
		)
	)
	(wire
		(pts
			(xy 278.13 95.25) (xy 276.86 95.25)
		)
		(stroke
			(width 0)
			(type default)
		)
	)
	(wire
		(pts
			(xy 195.58 59.69) (xy 193.04 59.69)
		)
		(stroke
			(width 0)
			(type default)
		)
	)
	(wire
		(pts
			(xy 365.76 48.26) (xy 375.92 48.26)
		)
		(stroke
			(width 0)
			(type default)
		)
	)
	(wire
		(pts
			(xy 278.13 90.17) (xy 276.86 90.17)
		)
		(stroke
			(width 0)
			(type default)
		)
	)
	(wire
		(pts
			(xy 365.76 142.24) (xy 375.92 142.24)
		)
		(stroke
			(width 0)
			(type default)
		)
	)
	(wire
		(pts
			(xy 88.9 252.73) (xy 86.36 252.73)
		)
		(stroke
			(width 0)
			(type default)
		)
	)
	(wire
		(pts
			(xy 278.13 78.74) (xy 276.86 78.74)
		)
		(stroke
			(width 0)
			(type default)
		)
	)
	(polyline
		(pts
			(xy 317.5 13.97) (xy 317.5 251.46)
		)
		(stroke
			(width 0)
			(type default)
		)
	)
	(wire
		(pts
			(xy 41.91 152.4) (xy 41.91 153.67)
		)
		(stroke
			(width 0)
			(type default)
		)
	)
	(wire
		(pts
			(xy 91.44 36.83) (xy 64.77 36.83)
		)
		(stroke
			(width 0)
			(type default)
		)
	)
	(wire
		(pts
			(xy 365.76 57.15) (xy 375.92 57.15)
		)
		(stroke
			(width 0)
			(type default)
		)
	)
	(wire
		(pts
			(xy 34.29 109.22) (xy 38.1 109.22)
		)
		(stroke
			(width 0)
			(type default)
		)
	)
	(wire
		(pts
			(xy 54.61 135.89) (xy 55.88 135.89)
		)
		(stroke
			(width 0)
			(type default)
		)
	)
	(wire
		(pts
			(xy 276.86 109.22) (xy 293.37 109.22)
		)
		(stroke
			(width 0)
			(type default)
		)
	)
	(wire
		(pts
			(xy 365.76 115.57) (xy 375.92 115.57)
		)
		(stroke
			(width 0)
			(type default)
		)
	)
	(wire
		(pts
			(xy 113.03 163.83) (xy 113.03 165.1)
		)
		(stroke
			(width 0)
			(type default)
		)
	)
	(wire
		(pts
			(xy 193.04 72.39) (xy 194.31 72.39)
		)
		(stroke
			(width 0)
			(type default)
		)
	)
	(wire
		(pts
			(xy 194.31 151.13) (xy 193.04 151.13)
		)
		(stroke
			(width 0)
			(type default)
		)
	)
	(wire
		(pts
			(xy 110.49 163.83) (xy 110.49 165.1)
		)
		(stroke
			(width 0)
			(type default)
		)
	)
	(wire
		(pts
			(xy 194.31 102.87) (xy 193.04 102.87)
		)
		(stroke
			(width 0)
			(type default)
		)
	)
	(wire
		(pts
			(xy 189.23 242.57) (xy 194.31 242.57)
		)
		(stroke
			(width 0)
			(type default)
		)
	)
	(wire
		(pts
			(xy 105.41 163.83) (xy 110.49 163.83)
		)
		(stroke
			(width 0)
			(type default)
		)
	)
	(wire
		(pts
			(xy 375.92 41.91) (xy 365.76 41.91)
		)
		(stroke
			(width 0)
			(type default)
		)
	)
	(wire
		(pts
			(xy 278.13 38.1) (xy 276.86 38.1)
		)
		(stroke
			(width 0)
			(type default)
		)
	)
	(wire
		(pts
			(xy 365.76 113.03) (xy 375.92 113.03)
		)
		(stroke
			(width 0)
			(type default)
		)
	)
	(wire
		(pts
			(xy 80.01 31.75) (xy 91.44 31.75)
		)
		(stroke
			(width 0)
			(type default)
		)
	)
	(wire
		(pts
			(xy 193.04 133.35) (xy 194.31 133.35)
		)
		(stroke
			(width 0)
			(type default)
		)
	)
	(wire
		(pts
			(xy 80.01 60.96) (xy 91.44 60.96)
		)
		(stroke
			(width 0)
			(type default)
		)
	)
	(wire
		(pts
			(xy 91.44 29.21) (xy 64.77 29.21)
		)
		(stroke
			(width 0)
			(type default)
		)
	)
	(wire
		(pts
			(xy 365.76 73.66) (xy 375.92 73.66)
		)
		(stroke
			(width 0)
			(type default)
		)
	)
	(wire
		(pts
			(xy 31.75 146.05) (xy 41.91 146.05)
		)
		(stroke
			(width 0)
			(type default)
		)
	)
	(wire
		(pts
			(xy 365.76 139.7) (xy 375.92 139.7)
		)
		(stroke
			(width 0)
			(type default)
		)
	)
	(wire
		(pts
			(xy 60.96 234.95) (xy 60.96 236.22)
		)
		(stroke
			(width 0)
			(type default)
		)
	)
	(wire
		(pts
			(xy 71.12 54.61) (xy 64.77 54.61)
		)
		(stroke
			(width 0)
			(type default)
		)
	)
	(wire
		(pts
			(xy 54.61 165.1) (xy 54.61 163.83)
		)
		(stroke
			(width 0)
			(type default)
		)
	)
	(wire
		(pts
			(xy 278.13 50.8) (xy 276.86 50.8)
		)
		(stroke
			(width 0)
			(type default)
		)
	)
	(wire
		(pts
			(xy 375.92 77.47) (xy 365.76 77.47)
		)
		(stroke
			(width 0)
			(type default)
		)
	)
	(wire
		(pts
			(xy 16.51 146.05) (xy 16.51 143.51)
		)
		(stroke
			(width 0)
			(type default)
		)
	)
	(wire
		(pts
			(xy 104.14 160.02) (xy 105.41 160.02)
		)
		(stroke
			(width 0)
			(type default)
		)
	)
	(wire
		(pts
			(xy 195.58 54.61) (xy 193.04 54.61)
		)
		(stroke
			(width 0)
			(type default)
		)
	)
	(wire
		(pts
			(xy 377.19 242.57) (xy 367.03 242.57)
		)
		(stroke
			(width 0)
			(type default)
		)
	)
	(wire
		(pts
			(xy 278.13 68.58) (xy 276.86 68.58)
		)
		(stroke
			(width 0)
			(type default)
		)
	)
	(wire
		(pts
			(xy 194.31 115.57) (xy 193.04 115.57)
		)
		(stroke
			(width 0)
			(type default)
		)
	)
	(wire
		(pts
			(xy 38.1 109.22) (xy 38.1 110.49)
		)
		(stroke
			(width 0)
			(type default)
		)
	)
	(wire
		(pts
			(xy 278.13 40.64) (xy 276.86 40.64)
		)
		(stroke
			(width 0)
			(type default)
		)
	)
	(wire
		(pts
			(xy 375.92 88.9) (xy 365.76 88.9)
		)
		(stroke
			(width 0)
			(type default)
		)
	)
	(wire
		(pts
			(xy 278.13 189.23) (xy 283.21 189.23)
		)
		(stroke
			(width 0)
			(type default)
		)
	)
	(wire
		(pts
			(xy 46.99 109.22) (xy 46.99 110.49)
		)
		(stroke
			(width 0)
			(type default)
		)
	)
	(wire
		(pts
			(xy 189.23 205.74) (xy 194.31 205.74)
		)
		(stroke
			(width 0)
			(type default)
		)
	)
	(wire
		(pts
			(xy 91.44 52.07) (xy 64.77 52.07)
		)
		(stroke
			(width 0)
			(type default)
		)
	)
	(wire
		(pts
			(xy 375.92 148.59) (xy 365.76 148.59)
		)
		(stroke
			(width 0)
			(type default)
		)
	)
	(wire
		(pts
			(xy 279.4 121.92) (xy 276.86 121.92)
		)
		(stroke
			(width 0)
			(type default)
		)
	)
	(wire
		(pts
			(xy 194.31 113.03) (xy 193.04 113.03)
		)
		(stroke
			(width 0)
			(type default)
		)
	)
	(wire
		(pts
			(xy 278.13 45.72) (xy 276.86 45.72)
		)
		(stroke
			(width 0)
			(type default)
		)
	)
	(wire
		(pts
			(xy 278.13 222.25) (xy 283.21 222.25)
		)
		(stroke
			(width 0)
			(type default)
		)
	)
	(wire
		(pts
			(xy 287.02 116.84) (xy 295.91 116.84)
		)
		(stroke
			(width 0)
			(type default)
		)
	)
	(wire
		(pts
			(xy 46.99 109.22) (xy 54.61 109.22)
		)
		(stroke
			(width 0)
			(type default)
		)
	)
	(wire
		(pts
			(xy 375.92 93.98) (xy 365.76 93.98)
		)
		(stroke
			(width 0)
			(type default)
		)
	)
	(wire
		(pts
			(xy 375.92 100.33) (xy 365.76 100.33)
		)
		(stroke
			(width 0)
			(type default)
		)
	)
	(wire
		(pts
			(xy 38.1 115.57) (xy 38.1 116.84)
		)
		(stroke
			(width 0)
			(type default)
		)
	)
	(wire
		(pts
			(xy 194.31 153.67) (xy 193.04 153.67)
		)
		(stroke
			(width 0)
			(type default)
		)
	)
	(wire
		(pts
			(xy 365.76 118.11) (xy 375.92 118.11)
		)
		(stroke
			(width 0)
			(type default)
		)
	)
	(wire
		(pts
			(xy 151.13 273.05) (xy 152.4 273.05)
		)
		(stroke
			(width 0)
			(type default)
		)
	)
	(wire
		(pts
			(xy 189.23 222.25) (xy 194.31 222.25)
		)
		(stroke
			(width 0)
			(type default)
		)
	)
	(wire
		(pts
			(xy 110.49 147.32) (xy 104.14 147.32)
		)
		(stroke
			(width 0)
			(type default)
		)
	)
	(wire
		(pts
			(xy 74.93 63.5) (xy 68.58 63.5)
		)
		(stroke
			(width 0)
			(type default)
		)
	)
	(wire
		(pts
			(xy 91.44 41.91) (xy 64.77 41.91)
		)
		(stroke
			(width 0)
			(type default)
		)
	)
	(wire
		(pts
			(xy 91.44 39.37) (xy 64.77 39.37)
		)
		(stroke
			(width 0)
			(type default)
		)
	)
	(wire
		(pts
			(xy 189.23 194.31) (xy 194.31 194.31)
		)
		(stroke
			(width 0)
			(type default)
		)
	)
	(wire
		(pts
			(xy 365.76 133.35) (xy 375.92 133.35)
		)
		(stroke
			(width 0)
			(type default)
		)
	)
	(wire
		(pts
			(xy 189.23 191.77) (xy 194.31 191.77)
		)
		(stroke
			(width 0)
			(type default)
		)
	)
	(wire
		(pts
			(xy 195.58 41.91) (xy 193.04 41.91)
		)
		(stroke
			(width 0)
			(type default)
		)
	)
	(wire
		(pts
			(xy 113.03 176.53) (xy 110.49 176.53)
		)
		(stroke
			(width 0)
			(type default)
		)
	)
	(wire
		(pts
			(xy 104.14 144.78) (xy 110.49 144.78)
		)
		(stroke
			(width 0)
			(type default)
		)
	)
	(wire
		(pts
			(xy 278.13 203.2) (xy 283.21 203.2)
		)
		(stroke
			(width 0)
			(type default)
		)
	)
	(wire
		(pts
			(xy 104.14 156.21) (xy 118.11 156.21)
		)
		(stroke
			(width 0)
			(type default)
		)
	)
	(wire
		(pts
			(xy 104.14 153.67) (xy 118.11 153.67)
		)
		(stroke
			(width 0)
			(type default)
		)
	)
	(wire
		(pts
			(xy 375.92 102.87) (xy 365.76 102.87)
		)
		(stroke
			(width 0)
			(type default)
		)
	)
	(wire
		(pts
			(xy 80.01 54.61) (xy 91.44 54.61)
		)
		(stroke
			(width 0)
			(type default)
		)
	)
	(wire
		(pts
			(xy 281.94 116.84) (xy 276.86 116.84)
		)
		(stroke
			(width 0)
			(type default)
		)
	)
	(wire
		(pts
			(xy 194.31 138.43) (xy 193.04 138.43)
		)
		(stroke
			(width 0)
			(type default)
		)
	)
	(wire
		(pts
			(xy 365.76 59.69) (xy 375.92 59.69)
		)
		(stroke
			(width 0)
			(type default)
		)
	)
	(wire
		(pts
			(xy 60.96 242.57) (xy 60.96 243.84)
		)
		(stroke
			(width 0)
			(type default)
		)
	)
	(wire
		(pts
			(xy 195.58 46.99) (xy 193.04 46.99)
		)
		(stroke
			(width 0)
			(type default)
		)
	)
	(wire
		(pts
			(xy 278.13 43.18) (xy 276.86 43.18)
		)
		(stroke
			(width 0)
			(type default)
		)
	)
	(wire
		(pts
			(xy 46.99 115.57) (xy 46.99 116.84)
		)
		(stroke
			(width 0)
			(type default)
		)
	)
	(wire
		(pts
			(xy 189.23 214.63) (xy 194.31 214.63)
		)
		(stroke
			(width 0)
			(type default)
		)
	)
	(wire
		(pts
			(xy 375.92 154.94) (xy 365.76 154.94)
		)
		(stroke
			(width 0)
			(type default)
		)
	)
	(wire
		(pts
			(xy 91.44 242.57) (xy 91.44 243.84)
		)
		(stroke
			(width 0)
			(type default)
		)
	)
	(wire
		(pts
			(xy 365.76 166.37) (xy 375.92 166.37)
		)
		(stroke
			(width 0)
			(type default)
		)
	)
	(wire
		(pts
			(xy 115.57 49.53) (xy 116.84 49.53)
		)
		(stroke
			(width 0)
			(type default)
		)
	)
	(wire
		(pts
			(xy 365.76 163.83) (xy 375.92 163.83)
		)
		(stroke
			(width 0)
			(type default)
		)
	)
	(wire
		(pts
			(xy 45.72 255.27) (xy 66.04 255.27)
		)
		(stroke
			(width 0)
			(type default)
		)
	)
	(wire
		(pts
			(xy 278.13 86.36) (xy 276.86 86.36)
		)
		(stroke
			(width 0)
			(type default)
		)
	)
	(wire
		(pts
			(xy 278.13 215.9) (xy 283.21 215.9)
		)
		(stroke
			(width 0)
			(type default)
		)
	)
	(wire
		(pts
			(xy 276.86 114.3) (xy 293.37 114.3)
		)
		(stroke
			(width 0)
			(type default)
		)
	)
	(wire
		(pts
			(xy 91.44 46.99) (xy 64.77 46.99)
		)
		(stroke
			(width 0)
			(type default)
		)
	)
	(wire
		(pts
			(xy 115.57 40.64) (xy 115.57 41.91)
		)
		(stroke
			(width 0)
			(type default)
		)
	)
	(polyline
		(pts
			(xy 228.6 165.1) (xy 317.5 165.1)
		)
		(stroke
			(width 0)
			(type default)
		)
	)
	(wire
		(pts
			(xy 91.44 236.22) (xy 91.44 237.49)
		)
		(stroke
			(width 0)
			(type default)
		)
	)
	(wire
		(pts
			(xy 365.76 50.8) (xy 375.92 50.8)
		)
		(stroke
			(width 0)
			(type default)
		)
	)
	(wire
		(pts
			(xy 365.76 54.61) (xy 375.92 54.61)
		)
		(stroke
			(width 0)
			(type default)
		)
	)
	(wire
		(pts
			(xy 278.13 97.79) (xy 276.86 97.79)
		)
		(stroke
			(width 0)
			(type default)
		)
	)
	(wire
		(pts
			(xy 365.76 161.29) (xy 375.92 161.29)
		)
		(stroke
			(width 0)
			(type default)
		)
	)
	(wire
		(pts
			(xy 91.44 236.22) (xy 87.63 236.22)
		)
		(stroke
			(width 0)
			(type default)
		)
	)
	(wire
		(pts
			(xy 189.23 198.12) (xy 194.31 198.12)
		)
		(stroke
			(width 0)
			(type default)
		)
	)
	(wire
		(pts
			(xy 195.58 44.45) (xy 193.04 44.45)
		)
		(stroke
			(width 0)
			(type default)
		)
	)
	(wire
		(pts
			(xy 195.58 57.15) (xy 193.04 57.15)
		)
		(stroke
			(width 0)
			(type default)
		)
	)
	(wire
		(pts
			(xy 377.19 213.36) (xy 367.03 213.36)
		)
		(stroke
			(width 0)
			(type default)
		)
	)
	(wire
		(pts
			(xy 278.13 66.04) (xy 276.86 66.04)
		)
		(stroke
			(width 0)
			(type default)
		)
	)
	(wire
		(pts
			(xy 375.92 96.52) (xy 365.76 96.52)
		)
		(stroke
			(width 0)
			(type default)
		)
	)
	(wire
		(pts
			(xy 278.13 199.39) (xy 283.21 199.39)
		)
		(stroke
			(width 0)
			(type default)
		)
	)
	(wire
		(pts
			(xy 64.77 31.75) (xy 74.93 31.75)
		)
		(stroke
			(width 0)
			(type default)
		)
	)
	(wire
		(pts
			(xy 189.23 248.92) (xy 194.31 248.92)
		)
		(stroke
			(width 0)
			(type default)
		)
	)
	(wire
		(pts
			(xy 113.03 176.53) (xy 113.03 177.8)
		)
		(stroke
			(width 0)
			(type default)
		)
	)
	(text "DEBUG UART LEVEL SHIFTER"
		(exclude_from_sim no)
		(at 62.23 227.33 0)
		(effects
			(font
				(size 1.27 1.27)
				(thickness 0.254)
				(bold yes)
			)
			(justify left bottom)
		)
	)
	(text "CSI"
		(exclude_from_sim no)
		(at 231.14 19.05 0)
		(effects
			(font
				(size 2 2)
				(thickness 0.508)
				(bold yes)
			)
			(justify left bottom)
		)
	)
	(text "Video Output"
		(exclude_from_sim no)
		(at 231.14 172.72 0)
		(effects
			(font
				(size 2 2)
				(thickness 0.508)
				(bold yes)
			)
			(justify left bottom)
		)
	)
	(text "Power & CTRL"
		(exclude_from_sim no)
		(at 19.05 72.39 0)
		(effects
			(font
				(size 2 2)
				(thickness 0.508)
				(bold yes)
			)
			(justify left bottom)
		)
	)
	(text "UART/I2C/SPI/I2S/CAN"
		(exclude_from_sim no)
		(at 143.51 19.05 0)
		(effects
			(font
				(size 2 2)
				(thickness 0.508)
				(bold yes)
			)
			(justify left bottom)
		)
	)
	(text "PCIe"
		(exclude_from_sim no)
		(at 320.04 19.05 0)
		(effects
			(font
				(size 2 2)
				(thickness 0.508)
				(bold yes)
			)
			(justify left bottom)
		)
	)
	(text "GbE"
		(exclude_from_sim no)
		(at 320.04 198.12 0)
		(effects
			(font
				(size 2 2)
				(thickness 0.508)
				(bold yes)
			)
			(justify left bottom)
		)
	)
	(text "USB"
		(exclude_from_sim no)
		(at 142.24 172.72 0)
		(effects
			(font
				(size 2 2)
				(thickness 0.508)
				(bold yes)
			)
			(justify left bottom)
		)
	)
	(text "GPIO"
		(exclude_from_sim no)
		(at 13.97 19.05 0)
		(effects
			(font
				(size 2 2)
				(thickness 0.508)
				(bold yes)
			)
			(justify left bottom)
		)
	)
	(text "Miscellaneous"
		(exclude_from_sim no)
		(at 64.77 223.52 0)
		(effects
			(font
				(size 2 2)
				(thickness 0.508)
				(bold yes)
			)
			(justify left bottom)
		)
	)
	(label "~{FORCE_RECOVERY}"
		(at 130.81 163.83 180)
		(effects
			(font
				(size 1.27 1.27)
			)
			(justify right bottom)
		)
	)
	(label "DEBUG_TXD_1V8"
		(at 45.72 255.27 0)
		(effects
			(font
				(size 1.27 1.27)
			)
			(justify left bottom)
		)
	)
	(label "SoM_VIN"
		(at 54.61 109.22 180)
		(effects
			(font
				(size 1.27 1.27)
			)
			(justify right bottom)
		)
	)
	(label "SLEEP{slash}~{WAKE}"
		(at 116.84 153.67 180)
		(effects
			(font
				(size 1.27 1.27)
			)
			(justify right bottom)
		)
	)
	(label "PMIC_BBAT"
		(at 53.34 142.24 180)
		(effects
			(font
				(size 1.27 1.27)
			)
			(justify right bottom)
		)
	)
	(label "DEBUG_RXD_1V8"
		(at 45.72 252.73 0)
		(effects
			(font
				(size 1.27 1.27)
			)
			(justify left bottom)
		)
	)
	(label "DEBUG_RXD_1V8"
		(at 215.9 67.31 180)
		(effects
			(font
				(size 1.27 1.27)
			)
			(justify right bottom)
		)
	)
	(label "~{MOD_SLEEP}"
		(at 116.84 156.21 180)
		(effects
			(font
				(size 1.27 1.27)
			)
			(justify right bottom)
		)
	)
	(label "DEBUG_TXD_1V8"
		(at 215.9 64.77 180)
		(effects
			(font
				(size 1.27 1.27)
			)
			(justify right bottom)
		)
	)
	(global_label "DP1_HPD"
		(shape output)
		(at 283.21 191.77 0)
		(effects
			(font
				(size 1.27 1.27)
			)
			(justify left)
		)
		(property "Intersheetrefs" "${INTERSHEET_REFS}"
			(at 297.18 191.77 0)
			(effects
				(font
					(size 1.27 1.27)
				)
				(justify left)
			)
		)
	)
	(global_label "DP1_TXD2_HDMI_TX0_N"
		(shape output)
		(at 283.21 218.44 0)
		(fields_autoplaced yes)
		(effects
			(font
				(size 1.27 1.27)
			)
			(justify left)
		)
		(property "Intersheetrefs" "${INTERSHEET_REFS}"
			(at 307.2736 218.3606 0)
			(effects
				(font
					(size 1.27 1.27)
				)
				(justify left)
			)
		)
	)
	(global_label "PCIE0_RX3_P"
		(shape bidirectional)
		(at 375.92 93.98 0)
		(effects
			(font
				(size 1.27 1.27)
			)
			(justify left)
		)
		(property "Intersheetrefs" "${INTERSHEET_REFS}"
			(at 394.335 93.98 0)
			(effects
				(font
					(size 1.27 1.27)
				)
				(justify left)
			)
		)
	)
	(global_label "USB1_D_N"
		(shape output)
		(at 194.31 242.57 0)
		(effects
			(font
				(size 1.27 1.27)
			)
			(justify left)
		)
		(property "Intersheetrefs" "${INTERSHEET_REFS}"
			(at 210.185 242.57 0)
			(effects
				(font
					(size 1.1 1.1)
				)
				(justify left)
			)
		)
	)
	(global_label "I2S0_SDIN"
		(shape input)
		(at 194.31 130.81 0)
		(effects
			(font
				(size 1.27 1.27)
			)
			(justify left)
		)
		(property "Intersheetrefs" "${INTERSHEET_REFS}"
			(at 208.28 130.81 0)
			(effects
				(font
					(size 1.27 1.27)
				)
				(justify left)
			)
		)
	)
	(global_label "CSI1_D0_P"
		(shape input)
		(at 278.13 60.96 0)
		(effects
			(font
				(size 1.27 1.27)
			)
			(justify left)
		)
		(property "Intersheetrefs" "${INTERSHEET_REFS}"
			(at 293.3096 60.96 0)
			(effects
				(font
					(size 1.27 1.27)
				)
				(justify left)
			)
		)
	)
	(global_label "PCIE2_RX1_N"
		(shape bidirectional)
		(at 375.92 168.91 0)
		(effects
			(font
				(size 1.27 1.27)
			)
			(justify left)
		)
		(property "Intersheetrefs" "${INTERSHEET_REFS}"
			(at 394.335 168.91 0)
			(effects
				(font
					(size 1.27 1.27)
				)
				(justify left)
			)
		)
	)
	(global_label "VSYNC_CAM0"
		(shape output)
		(at 295.91 116.84 0)
		(effects
			(font
				(size 1.27 1.27)
			)
			(justify left)
		)
		(property "Intersheetrefs" "${INTERSHEET_REFS}"
			(at 311.15 116.84 0)
			(effects
				(font
					(size 1.27 1.27)
				)
				(justify left)
			)
		)
	)
	(global_label "PCIE0_RX2_P"
		(shape bidirectional)
		(at 375.92 82.55 0)
		(effects
			(font
				(size 1.27 1.27)
			)
			(justify left)
		)
		(property "Intersheetrefs" "${INTERSHEET_REFS}"
			(at 394.335 82.55 0)
			(effects
				(font
					(size 1.27 1.27)
				)
				(justify left)
			)
		)
	)
	(global_label "CSI3_D0_P"
		(shape input)
		(at 278.13 95.25 0)
		(effects
			(font
				(size 1.27 1.27)
			)
			(justify left)
		)
		(property "Intersheetrefs" "${INTERSHEET_REFS}"
			(at 293.3096 95.25 0)
			(effects
				(font
					(size 1.27 1.27)
				)
				(justify left)
			)
		)
	)
	(global_label "PCIE2_CLK_P"
		(shape bidirectional)
		(at 375.92 130.81 0)
		(effects
			(font
				(size 1.27 1.27)
			)
			(justify left)
		)
		(property "Intersheetrefs" "${INTERSHEET_REFS}"
			(at 394.335 130.81 0)
			(effects
				(font
					(size 1.27 1.27)
				)
				(justify left)
			)
		)
	)
	(global_label "~{SHUTDOWN_REQ}"
		(shape output)
		(at 110.49 144.78 0)
		(effects
			(font
				(size 1.27 1.27)
			)
			(justify left)
		)
		(property "Intersheetrefs" "${INTERSHEET_REFS}"
			(at 128.27 144.78 0)
			(effects
				(font
					(size 1.27 1.27)
				)
				(justify left)
			)
		)
	)
	(global_label "CAN_RX"
		(shape input)
		(at 194.31 151.13 0)
		(effects
			(font
				(size 1.27 1.27)
			)
			(justify left)
		)
		(property "Intersheetrefs" "${INTERSHEET_REFS}"
			(at 205.74 151.13 0)
			(effects
				(font
					(size 1.27 1.27)
				)
				(justify left)
			)
		)
	)
	(global_label "~{SPI0_CS1}"
		(shape bidirectional)
		(at 194.31 105.41 0)
		(effects
			(font
				(size 1.27 1.27)
			)
			(justify left)
		)
		(property "Intersheetrefs" "${INTERSHEET_REFS}"
			(at 208.28 105.41 0)
			(effects
				(font
					(size 1.27 1.27)
				)
				(justify left)
			)
		)
	)
	(global_label "GPIO12"
		(shape bidirectional)
		(at 91.44 54.61 0)
		(effects
			(font
				(size 1.27 1.27)
			)
			(justify left)
		)
		(property "Intersheetrefs" "${INTERSHEET_REFS}"
			(at 106.045 54.61 0)
			(effects
				(font
					(size 1.27 1.27)
				)
				(justify left)
			)
		)
	)
	(global_label "CSI2_CLK_N"
		(shape input)
		(at 278.13 76.2 0)
		(effects
			(font
				(size 1.27 1.27)
			)
			(justify left)
		)
		(property "Intersheetrefs" "${INTERSHEET_REFS}"
			(at 293.4305 76.2 0)
			(effects
				(font
					(size 1.27 1.27)
				)
				(justify left)
			)
		)
	)
	(global_label "CSI3_D0_N"
		(shape input)
		(at 278.13 97.79 0)
		(effects
			(font
				(size 1.27 1.27)
			)
			(justify left)
		)
		(property "Intersheetrefs" "${INTERSHEET_REFS}"
			(at 293.37 97.79 0)
			(effects
				(font
					(size 1.27 1.27)
				)
				(justify left)
			)
		)
	)
	(global_label "PCIE0_TX2_P"
		(shape bidirectional)
		(at 375.92 77.47 0)
		(effects
			(font
				(size 1.27 1.27)
			)
			(justify left)
		)
		(property "Intersheetrefs" "${INTERSHEET_REFS}"
			(at 394.335 77.47 0)
			(effects
				(font
					(size 1.27 1.27)
				)
				(justify left)
			)
		)
	)
	(global_label "CSI2_D1_P"
		(shape input)
		(at 278.13 83.82 0)
		(effects
			(font
				(size 1.27 1.27)
			)
			(justify left)
		)
		(property "Intersheetrefs" "${INTERSHEET_REFS}"
			(at 293.3096 83.82 0)
			(effects
				(font
					(size 1.27 1.27)
				)
				(justify left)
			)
		)
	)
	(global_label "GPIO07"
		(shape bidirectional)
		(at 91.44 44.45 0)
		(effects
			(font
				(size 1.27 1.27)
			)
			(justify left)
		)
		(property "Intersheetrefs" "${INTERSHEET_REFS}"
			(at 106.045 44.45 0)
			(effects
				(font
					(size 1.27 1.27)
				)
				(justify left)
			)
		)
	)
	(global_label "SPI1_SCK"
		(shape output)
		(at 194.31 110.49 0)
		(effects
			(font
				(size 1.27 1.27)
			)
			(justify left)
		)
		(property "Intersheetrefs" "${INTERSHEET_REFS}"
			(at 208.28 110.49 0)
			(effects
				(font
					(size 1.27 1.27)
				)
				(justify left)
			)
		)
	)
	(global_label "USER_LED0"
		(shape output)
		(at 91.44 34.29 0)
		(effects
			(font
				(size 1.27 1.27)
			)
			(justify left)
		)
		(property "Intersheetrefs" "${INTERSHEET_REFS}"
			(at 106.045 34.29 0)
			(effects
				(font
					(size 1.27 1.27)
				)
				(justify left)
			)
		)
	)
	(global_label "PCIE3_CLKREQ*"
		(shape bidirectional)
		(at 375.92 151.13 0)
		(effects
			(font
				(size 1.27 1.27)
			)
			(justify left)
		)
		(property "Intersheetrefs" "${INTERSHEET_REFS}"
			(at 394.335 151.13 0)
			(effects
				(font
					(size 1.27 1.27)
				)
				(justify left)
			)
		)
	)
	(global_label "USBSS1_TX_N"
		(shape output)
		(at 194.31 208.28 0)
		(effects
			(font
				(size 1.27 1.27)
			)
			(justify left)
		)
		(property "Intersheetrefs" "${INTERSHEET_REFS}"
			(at 210.185 208.28 0)
			(effects
				(font
					(size 1.1 1.1)
				)
				(justify left)
			)
		)
	)
	(global_label "CSI1_D1_N"
		(shape input)
		(at 278.13 68.58 0)
		(effects
			(font
				(size 1.27 1.27)
			)
			(justify left)
		)
		(property "Intersheetrefs" "${INTERSHEET_REFS}"
			(at 293.37 68.58 0)
			(effects
				(font
					(size 1.27 1.27)
				)
				(justify left)
			)
		)
	)
	(global_label "UART0_RXD"
		(shape input)
		(at 195.58 46.99 0)
		(effects
			(font
				(size 1.27 1.27)
			)
			(justify left)
		)
		(property "Intersheetrefs" "${INTERSHEET_REFS}"
			(at 209.55 46.99 0)
			(effects
				(font
					(size 1.27 1.27)
				)
				(justify left)
			)
		)
	)
	(global_label "DP1_TXD1_HDMI_TX1_N"
		(shape output)
		(at 283.21 212.09 0)
		(fields_autoplaced yes)
		(effects
			(font
				(size 1.27 1.27)
			)
			(justify left)
		)
		(property "Intersheetrefs" "${INTERSHEET_REFS}"
			(at 307.2736 212.0106 0)
			(effects
				(font
					(size 1.27 1.27)
				)
				(justify left)
			)
		)
	)
	(global_label "PCIE2_TX1_P"
		(shape bidirectional)
		(at 375.92 161.29 0)
		(effects
			(font
				(size 1.27 1.27)
			)
			(justify left)
		)
		(property "Intersheetrefs" "${INTERSHEET_REFS}"
			(at 394.335 161.29 0)
			(effects
				(font
					(size 1.27 1.27)
				)
				(justify left)
			)
		)
	)
	(global_label "PCIE0_CLKREQ*"
		(shape bidirectional)
		(at 375.92 44.45 0)
		(effects
			(font
				(size 1.27 1.27)
			)
			(justify left)
		)
		(property "Intersheetrefs" "${INTERSHEET_REFS}"
			(at 394.335 44.45 0)
			(effects
				(font
					(size 1.27 1.27)
				)
				(justify left)
			)
		)
	)
	(global_label "I2S0_LRCK"
		(shape output)
		(at 194.31 133.35 0)
		(effects
			(font
				(size 1.27 1.27)
			)
			(justify left)
		)
		(property "Intersheetrefs" "${INTERSHEET_REFS}"
			(at 208.28 133.35 0)
			(effects
				(font
					(size 1.27 1.27)
				)
				(justify left)
			)
		)
	)
	(global_label "PCIE2_RX1_P"
		(shape bidirectional)
		(at 375.92 166.37 0)
		(effects
			(font
				(size 1.27 1.27)
			)
			(justify left)
		)
		(property "Intersheetrefs" "${INTERSHEET_REFS}"
			(at 394.335 166.37 0)
			(effects
				(font
					(size 1.27 1.27)
				)
				(justify left)
			)
		)
	)
	(global_label "USBSS2_RX_P"
		(shape output)
		(at 194.31 226.06 0)
		(effects
			(font
				(size 1.27 1.27)
			)
			(justify left)
		)
		(property "Intersheetrefs" "${INTERSHEET_REFS}"
			(at 210.185 226.06 0)
			(effects
				(font
					(size 1.1 1.1)
				)
				(justify left)
			)
		)
	)
	(global_label "GPIO01"
		(shape bidirectional)
		(at 91.44 29.21 0)
		(effects
			(font
				(size 1.27 1.27)
			)
			(justify left)
		)
		(property "Intersheetrefs" "${INTERSHEET_REFS}"
			(at 106.045 29.21 0)
			(effects
				(font
					(size 1.27 1.27)
				)
				(justify left)
			)
		)
	)
	(global_label "VSYNC_CAM3"
		(shape output)
		(at 91.44 63.5 0)
		(effects
			(font
				(size 1.27 1.27)
			)
			(justify left)
		)
		(property "Intersheetrefs" "${INTERSHEET_REFS}"
			(at 106.68 63.5 0)
			(effects
				(font
					(size 1.27 1.27)
				)
				(justify left)
			)
		)
	)
	(global_label "USB2_D_N"
		(shape output)
		(at 194.31 248.92 0)
		(effects
			(font
				(size 1.27 1.27)
			)
			(justify left)
		)
		(property "Intersheetrefs" "${INTERSHEET_REFS}"
			(at 210.185 248.92 0)
			(effects
				(font
					(size 1.1 1.1)
				)
				(justify left)
			)
		)
	)
	(global_label "SPIO_MISO"
		(shape input)
		(at 194.31 100.33 0)
		(effects
			(font
				(size 1.27 1.27)
			)
			(justify left)
		)
		(property "Intersheetrefs" "${INTERSHEET_REFS}"
			(at 208.28 100.33 0)
			(effects
				(font
					(size 1.27 1.27)
				)
				(justify left)
			)
		)
	)
	(global_label "I2C1_SCL"
		(shape output)
		(at 194.31 80.01 0)
		(effects
			(font
				(size 1.27 1.27)
			)
			(justify left)
		)
		(property "Intersheetrefs" "${INTERSHEET_REFS}"
			(at 208.28 80.01 0)
			(effects
				(font
					(size 1.27 1.27)
				)
				(justify left)
			)
		)
	)
	(global_label "USBSS1_RX_N"
		(shape output)
		(at 194.31 214.63 0)
		(effects
			(font
				(size 1.27 1.27)
			)
			(justify left)
		)
		(property "Intersheetrefs" "${INTERSHEET_REFS}"
			(at 210.185 214.63 0)
			(effects
				(font
					(size 1.1 1.1)
				)
				(justify left)
			)
		)
	)
	(global_label "PCIE3_CLK_P"
		(shape bidirectional)
		(at 375.92 154.94 0)
		(effects
			(font
				(size 1.27 1.27)
			)
			(justify left)
		)
		(property "Intersheetrefs" "${INTERSHEET_REFS}"
			(at 394.335 154.94 0)
			(effects
				(font
					(size 1.27 1.27)
				)
				(justify left)
			)
		)
	)
	(global_label "USBSS0_TX_P"
		(shape output)
		(at 194.31 191.77 0)
		(effects
			(font
				(size 1.27 1.27)
			)
			(justify left)
		)
		(property "Intersheetrefs" "${INTERSHEET_REFS}"
			(at 210.185 191.77 0)
			(effects
				(font
					(size 1.1 1.1)
				)
				(justify left)
			)
		)
	)
	(global_label "PCIE0_RX2_N"
		(shape bidirectional)
		(at 375.92 85.09 0)
		(effects
			(font
				(size 1.27 1.27)
			)
			(justify left)
		)
		(property "Intersheetrefs" "${INTERSHEET_REFS}"
			(at 394.335 85.09 0)
			(effects
				(font
					(size 1.27 1.27)
				)
				(justify left)
			)
		)
	)
	(global_label "~{SPI1_CS0}"
		(shape bidirectional)
		(at 194.31 118.11 0)
		(effects
			(font
				(size 1.27 1.27)
			)
			(justify left)
		)
		(property "Intersheetrefs" "${INTERSHEET_REFS}"
			(at 208.28 118.11 0)
			(effects
				(font
					(size 1.27 1.27)
				)
				(justify left)
			)
		)
	)
	(global_label "CSI0_CLK_N"
		(shape input)
		(at 278.13 40.64 0)
		(effects
			(font
				(size 1.27 1.27)
			)
			(justify left)
		)
		(property "Intersheetrefs" "${INTERSHEET_REFS}"
			(at 293.4305 40.64 0)
			(effects
				(font
					(size 1.27 1.27)
				)
				(justify left)
			)
		)
	)
	(global_label "UART1_TXD"
		(shape output)
		(at 195.58 57.15 0)
		(effects
			(font
				(size 1.27 1.27)
			)
			(justify left)
		)
		(property "Intersheetrefs" "${INTERSHEET_REFS}"
			(at 209.55 57.15 0)
			(effects
				(font
					(size 1.27 1.27)
				)
				(justify left)
			)
		)
	)
	(global_label "GBE_LED_ACT"
		(shape input)
		(at 377.19 215.9 0)
		(fields_autoplaced yes)
		(effects
			(font
				(size 1.27 1.27)
			)
			(justify left)
		)
		(property "Intersheetrefs" "${INTERSHEET_REFS}"
			(at 394.335 215.9 0)
			(effects
				(font
					(size 1.27 1.27)
				)
				(justify left)
			)
		)
	)
	(global_label "PCIE0_TX0_N"
		(shape bidirectional)
		(at 375.92 57.15 0)
		(effects
			(font
				(size 1.27 1.27)
			)
			(justify left)
		)
		(property "Intersheetrefs" "${INTERSHEET_REFS}"
			(at 394.335 57.15 0)
			(effects
				(font
					(size 1.27 1.27)
				)
				(justify left)
			)
		)
	)
	(global_label "DP1_TXD2_HDMI_TX0_P"
		(shape output)
		(at 283.21 215.9 0)
		(fields_autoplaced yes)
		(effects
			(font
				(size 1.27 1.27)
			)
			(justify left)
		)
		(property "Intersheetrefs" "${INTERSHEET_REFS}"
			(at 307.2131 215.8206 0)
			(effects
				(font
					(size 1.27 1.27)
				)
				(justify left)
			)
		)
	)
	(global_label "PCIE0_RX0_N"
		(shape bidirectional)
		(at 375.92 62.23 0)
		(effects
			(font
				(size 1.27 1.27)
			)
			(justify left)
		)
		(property "Intersheetrefs" "${INTERSHEET_REFS}"
			(at 394.335 62.23 0)
			(effects
				(font
					(size 1.27 1.27)
				)
				(justify left)
			)
		)
	)
	(global_label "PCIE1_CLK_P"
		(shape bidirectional)
		(at 375.92 106.68 0)
		(effects
			(font
				(size 1.27 1.27)
			)
			(justify left)
		)
		(property "Intersheetrefs" "${INTERSHEET_REFS}"
			(at 394.335 106.68 0)
			(effects
				(font
					(size 1.27 1.27)
				)
				(justify left)
			)
		)
	)
	(global_label "I2C2_SCL"
		(shape output)
		(at 194.31 86.36 0)
		(effects
			(font
				(size 1.27 1.27)
			)
			(justify left)
		)
		(property "Intersheetrefs" "${INTERSHEET_REFS}"
			(at 208.28 86.36 0)
			(effects
				(font
					(size 1.27 1.27)
				)
				(justify left)
			)
		)
	)
	(global_label "USBSS2_TX_P"
		(shape output)
		(at 194.31 219.71 0)
		(effects
			(font
				(size 1.27 1.27)
			)
			(justify left)
		)
		(property "Intersheetrefs" "${INTERSHEET_REFS}"
			(at 210.185 219.71 0)
			(effects
				(font
					(size 1.1 1.1)
				)
				(justify left)
			)
		)
	)
	(global_label "GBE_LED_LINK"
		(shape input)
		(at 377.19 213.36 0)
		(fields_autoplaced yes)
		(effects
			(font
				(size 1.27 1.27)
			)
			(justify left)
		)
		(property "Intersheetrefs" "${INTERSHEET_REFS}"
			(at 394.335 213.36 0)
			(effects
				(font
					(size 1.27 1.27)
				)
				(justify left)
			)
		)
	)
	(global_label "CSI3_D1_P"
		(shape input)
		(at 278.13 100.33 0)
		(effects
			(font
				(size 1.27 1.27)
			)
			(justify left)
		)
		(property "Intersheetrefs" "${INTERSHEET_REFS}"
			(at 293.3096 100.33 0)
			(effects
				(font
					(size 1.27 1.27)
				)
				(justify left)
			)
		)
	)
	(global_label "CSI1_D0_N"
		(shape input)
		(at 278.13 63.5 0)
		(effects
			(font
				(size 1.27 1.27)
			)
			(justify left)
		)
		(property "Intersheetrefs" "${INTERSHEET_REFS}"
			(at 293.37 63.5 0)
			(effects
				(font
					(size 1.27 1.27)
				)
				(justify left)
			)
		)
	)
	(global_label "CSI1_CLK_N"
		(shape input)
		(at 278.13 58.42 0)
		(effects
			(font
				(size 1.27 1.27)
			)
			(justify left)
		)
		(property "Intersheetrefs" "${INTERSHEET_REFS}"
			(at 293.4305 58.42 0)
			(effects
				(font
					(size 1.27 1.27)
				)
				(justify left)
			)
		)
	)
	(global_label "GBE_MDI2_N"
		(shape input)
		(at 377.19 236.22 0)
		(fields_autoplaced yes)
		(effects
			(font
				(size 1.27 1.27)
			)
			(justify left)
		)
		(property "Intersheetrefs" "${INTERSHEET_REFS}"
			(at 394.335 236.22 0)
			(effects
				(font
					(size 1.27 1.27)
				)
				(justify left)
			)
		)
	)
	(global_label "FAN_PWM"
		(shape output)
		(at 110.49 139.7 0)
		(effects
			(font
				(size 1.27 1.27)
			)
			(justify left)
		)
		(property "Intersheetrefs" "${INTERSHEET_REFS}"
			(at 128.27 139.7 0)
			(effects
				(font
					(size 1.27 1.27)
				)
				(justify left)
			)
		)
	)
	(global_label "CSI0_D0_N"
		(shape input)
		(at 278.13 45.72 0)
		(effects
			(font
				(size 1.27 1.27)
			)
			(justify left)
		)
		(property "Intersheetrefs" "${INTERSHEET_REFS}"
			(at 293.37 45.72 0)
			(effects
				(font
					(size 1.27 1.27)
				)
				(justify left)
			)
		)
	)
	(global_label "I2C1_SDA"
		(shape bidirectional)
		(at 194.31 82.55 0)
		(effects
			(font
				(size 1.27 1.27)
			)
			(justify left)
		)
		(property "Intersheetrefs" "${INTERSHEET_REFS}"
			(at 208.28 82.55 0)
			(effects
				(font
					(size 1.27 1.27)
				)
				(justify left)
			)
		)
	)
	(global_label "USB0_D_N"
		(shape output)
		(at 194.31 236.22 0)
		(effects
			(font
				(size 1.27 1.27)
			)
			(justify left)
		)
		(property "Intersheetrefs" "${INTERSHEET_REFS}"
			(at 210.185 236.22 0)
			(effects
				(font
					(size 1.1 1.1)
				)
				(justify left)
			)
		)
	)
	(global_label "PCIE0_TX3_N"
		(shape bidirectional)
		(at 375.92 91.44 0)
		(effects
			(font
				(size 1.27 1.27)
			)
			(justify left)
		)
		(property "Intersheetrefs" "${INTERSHEET_REFS}"
			(at 394.335 91.44 0)
			(effects
				(font
					(size 1.27 1.27)
				)
				(justify left)
			)
		)
	)
	(global_label "PCIE3_RST*"
		(shape bidirectional)
		(at 375.92 148.59 0)
		(effects
			(font
				(size 1.27 1.27)
			)
			(justify left)
		)
		(property "Intersheetrefs" "${INTERSHEET_REFS}"
			(at 394.335 148.59 0)
			(effects
				(font
					(size 1.27 1.27)
				)
				(justify left)
			)
		)
	)
	(global_label "PCIE0_TX0_P"
		(shape bidirectional)
		(at 375.92 54.61 0)
		(effects
			(font
				(size 1.27 1.27)
			)
			(justify left)
		)
		(property "Intersheetrefs" "${INTERSHEET_REFS}"
			(at 394.335 54.61 0)
			(effects
				(font
					(size 1.27 1.27)
				)
				(justify left)
			)
		)
	)
	(global_label "PCIE0_RX0_P"
		(shape bidirectional)
		(at 375.92 59.69 0)
		(effects
			(font
				(size 1.27 1.27)
			)
			(justify left)
		)
		(property "Intersheetrefs" "${INTERSHEET_REFS}"
			(at 394.335 59.69 0)
			(effects
				(font
					(size 1.27 1.27)
				)
				(justify left)
			)
		)
	)
	(global_label "DP1_TXD3_HDMI_TXC_P"
		(shape output)
		(at 283.21 222.25 0)
		(fields_autoplaced yes)
		(effects
			(font
				(size 1.27 1.27)
			)
			(justify left)
		)
		(property "Intersheetrefs" "${INTERSHEET_REFS}"
			(at 307.2736 222.1706 0)
			(effects
				(font
					(size 1.27 1.27)
				)
				(justify left)
			)
		)
	)
	(global_label "I2S1_SDOUT"
		(shape output)
		(at 194.31 140.97 0)
		(effects
			(font
				(size 1.27 1.27)
			)
			(justify left)
		)
		(property "Intersheetrefs" "${INTERSHEET_REFS}"
			(at 208.28 140.97 0)
			(effects
				(font
					(size 1.27 1.27)
				)
				(justify left)
			)
		)
	)
	(global_label "PCIE2_CLKREQ*"
		(shape bidirectional)
		(at 375.92 127 0)
		(effects
			(font
				(size 1.27 1.27)
			)
			(justify left)
		)
		(property "Intersheetrefs" "${INTERSHEET_REFS}"
			(at 394.335 127 0)
			(effects
				(font
					(size 1.27 1.27)
				)
				(justify left)
			)
		)
	)
	(global_label "DP1_HDMI_AUX_P"
		(shape output)
		(at 283.21 196.85 0)
		(fields_autoplaced yes)
		(effects
			(font
				(size 1.27 1.27)
			)
			(justify left)
		)
		(property "Intersheetrefs" "${INTERSHEET_REFS}"
			(at 301.8307 196.7706 0)
			(effects
				(font
					(size 1.27 1.27)
				)
				(justify left)
			)
		)
	)
	(global_label "PCIE0_RST*"
		(shape bidirectional)
		(at 375.92 41.91 0)
		(effects
			(font
				(size 1.27 1.27)
			)
			(justify left)
		)
		(property "Intersheetrefs" "${INTERSHEET_REFS}"
			(at 394.335 41.91 0)
			(effects
				(font
					(size 1.27 1.27)
				)
				(justify left)
			)
		)
	)
	(global_label "USB_FLASH_ID"
		(shape input)
		(at 194.31 186.69 0)
		(fields_autoplaced yes)
		(effects
			(font
				(size 1.27 1.27)
			)
			(justify left)
		)
		(property "Intersheetrefs" "${INTERSHEET_REFS}"
			(at 210.0883 186.6106 0)
			(effects
				(font
					(size 1.27 1.27)
				)
				(justify left)
			)
		)
	)
	(global_label "POWER_EN"
		(shape input)
		(at 110.49 147.32 0)
		(effects
			(font
				(size 1.27 1.27)
			)
			(justify left)
		)
		(property "Intersheetrefs" "${INTERSHEET_REFS}"
			(at 128.27 147.32 0)
			(effects
				(font
					(size 1.27 1.27)
				)
				(justify left)
			)
		)
	)
	(global_label "USB1_D_P"
		(shape output)
		(at 194.31 240.03 0)
		(effects
			(font
				(size 1.27 1.27)
			)
			(justify left)
		)
		(property "Intersheetrefs" "${INTERSHEET_REFS}"
			(at 210.185 240.03 0)
			(effects
				(font
					(size 1.1 1.1)
				)
				(justify left)
			)
		)
	)
	(global_label "USER_BTN0"
		(shape input)
		(at 91.44 39.37 0)
		(effects
			(font
				(size 1.27 1.27)
			)
			(justify left)
		)
		(property "Intersheetrefs" "${INTERSHEET_REFS}"
			(at 106.045 39.37 0)
			(effects
				(font
					(size 1.27 1.27)
				)
				(justify left)
			)
		)
	)
	(global_label "~{SPI1_CS1}"
		(shape bidirectional)
		(at 194.31 120.65 0)
		(effects
			(font
				(size 1.27 1.27)
			)
			(justify left)
		)
		(property "Intersheetrefs" "${INTERSHEET_REFS}"
			(at 208.28 120.65 0)
			(effects
				(font
					(size 1.27 1.27)
				)
				(justify left)
			)
		)
	)
	(global_label "PCIE2_RX0_P"
		(shape bidirectional)
		(at 375.92 142.24 0)
		(effects
			(font
				(size 1.27 1.27)
			)
			(justify left)
		)
		(property "Intersheetrefs" "${INTERSHEET_REFS}"
			(at 394.335 142.24 0)
			(effects
				(font
					(size 1.27 1.27)
				)
				(justify left)
			)
		)
	)
	(global_label "DP1_TXD0_HDMI_TX2_N"
		(shape output)
		(at 283.21 205.74 0)
		(fields_autoplaced yes)
		(effects
			(font
				(size 1.27 1.27)
			)
			(justify left)
		)
		(property "Intersheetrefs" "${INTERSHEET_REFS}"
			(at 307.2736 205.6606 0)
			(effects
				(font
					(size 1.27 1.27)
				)
				(justify left)
			)
		)
	)
	(global_label "USB2_D_P"
		(shape output)
		(at 194.31 246.38 0)
		(effects
			(font
				(size 1.27 1.27)
			)
			(justify left)
		)
		(property "Intersheetrefs" "${INTERSHEET_REFS}"
			(at 210.185 246.38 0)
			(effects
				(font
					(size 1.1 1.1)
				)
				(justify left)
			)
		)
	)
	(global_label "SDA_CAM"
		(shape bidirectional)
		(at 278.13 124.46 0)
		(effects
			(font
				(size 1.27 1.27)
			)
			(justify left)
		)
		(property "Intersheetrefs" "${INTERSHEET_REFS}"
			(at 293.37 124.46 0)
			(effects
				(font
					(size 1.27 1.27)
				)
				(justify left)
			)
		)
	)
	(global_label "SPIO_MOSI"
		(shape output)
		(at 194.31 97.79 0)
		(effects
			(font
				(size 1.27 1.27)
			)
			(justify left)
		)
		(property "Intersheetrefs" "${INTERSHEET_REFS}"
			(at 208.28 97.79 0)
			(effects
				(font
					(size 1.27 1.27)
				)
				(justify left)
			)
		)
	)
	(global_label "~{SPI0_CS0}"
		(shape bidirectional)
		(at 194.31 102.87 0)
		(effects
			(font
				(size 1.27 1.27)
			)
			(justify left)
		)
		(property "Intersheetrefs" "${INTERSHEET_REFS}"
			(at 208.28 102.87 0)
			(effects
				(font
					(size 1.27 1.27)
				)
				(justify left)
			)
		)
	)
	(global_label "GBE_MDI0_P"
		(shape input)
		(at 377.19 220.98 0)
		(fields_autoplaced yes)
		(effects
			(font
				(size 1.27 1.27)
			)
			(justify left)
		)
		(property "Intersheetrefs" "${INTERSHEET_REFS}"
			(at 394.335 220.98 0)
			(effects
				(font
					(size 1.27 1.27)
				)
				(justify left)
			)
		)
	)
	(global_label "USBSS0_RX_P"
		(shape output)
		(at 194.31 198.12 0)
		(effects
			(font
				(size 1.27 1.27)
			)
			(justify left)
		)
		(property "Intersheetrefs" "${INTERSHEET_REFS}"
			(at 210.185 198.12 0)
			(effects
				(font
					(size 1.1 1.1)
				)
				(justify left)
			)
		)
	)
	(global_label "SYS_SDA"
		(shape bidirectional)
		(at 194.31 74.93 0)
		(effects
			(font
				(size 1.27 1.27)
			)
			(justify left)
		)
		(property "Intersheetrefs" "${INTERSHEET_REFS}"
			(at 207.645 74.93 0)
			(effects
				(font
					(size 1.27 1.27)
				)
				(justify left)
			)
		)
	)
	(global_label "UART0_RTS"
		(shape bidirectional)
		(at 195.58 39.37 0)
		(effects
			(font
				(size 1.27 1.27)
			)
			(justify left)
		)
		(property "Intersheetrefs" "${INTERSHEET_REFS}"
			(at 209.55 39.37 0)
			(effects
				(font
					(size 1.27 1.27)
				)
				(justify left)
			)
		)
	)
	(global_label "PCIE2_RST*"
		(shape bidirectional)
		(at 375.92 124.46 0)
		(effects
			(font
				(size 1.27 1.27)
			)
			(justify left)
		)
		(property "Intersheetrefs" "${INTERSHEET_REFS}"
			(at 394.335 124.46 0)
			(effects
				(font
					(size 1.27 1.27)
				)
				(justify left)
			)
		)
	)
	(global_label "GBE_MDI3_N"
		(shape input)
		(at 377.19 242.57 0)
		(fields_autoplaced yes)
		(effects
			(font
				(size 1.27 1.27)
			)
			(justify left)
		)
		(property "Intersheetrefs" "${INTERSHEET_REFS}"
			(at 394.335 242.57 0)
			(effects
				(font
					(size 1.27 1.27)
				)
				(justify left)
			)
		)
	)
	(global_label "USB0_D_P"
		(shape output)
		(at 194.31 233.68 0)
		(effects
			(font
				(size 1.27 1.27)
			)
			(justify left)
		)
		(property "Intersheetrefs" "${INTERSHEET_REFS}"
			(at 210.185 233.68 0)
			(effects
				(font
					(size 1.1 1.1)
				)
				(justify left)
			)
		)
	)
	(global_label "USBSS1_RX_P"
		(shape output)
		(at 194.31 212.09 0)
		(effects
			(font
				(size 1.27 1.27)
			)
			(justify left)
		)
		(property "Intersheetrefs" "${INTERSHEET_REFS}"
			(at 210.185 212.09 0)
			(effects
				(font
					(size 1.1 1.1)
				)
				(justify left)
			)
		)
	)
	(global_label "PCIE0_CLK_N"
		(shape bidirectional)
		(at 375.92 50.8 0)
		(effects
			(font
				(size 1.27 1.27)
			)
			(justify left)
		)
		(property "Intersheetrefs" "${INTERSHEET_REFS}"
			(at 394.335 51.435 0)
			(effects
				(font
					(size 1.27 1.27)
				)
				(justify left)
			)
		)
	)
	(global_label "PCIE2_RX0_N"
		(shape bidirectional)
		(at 375.92 144.78 0)
		(effects
			(font
				(size 1.27 1.27)
			)
			(justify left)
		)
		(property "Intersheetrefs" "${INTERSHEET_REFS}"
			(at 394.335 144.78 0)
			(effects
				(font
					(size 1.27 1.27)
				)
				(justify left)
			)
		)
	)
	(global_label "UART0_CTS"
		(shape bidirectional)
		(at 195.58 41.91 0)
		(effects
			(font
				(size 1.27 1.27)
			)
			(justify left)
		)
		(property "Intersheetrefs" "${INTERSHEET_REFS}"
			(at 209.55 41.91 0)
			(effects
				(font
					(size 1.27 1.27)
				)
				(justify left)
			)
		)
	)
	(global_label "PCIE0_RX3_N"
		(shape bidirectional)
		(at 375.92 96.52 0)
		(effects
			(font
				(size 1.27 1.27)
			)
			(justify left)
		)
		(property "Intersheetrefs" "${INTERSHEET_REFS}"
			(at 394.335 96.52 0)
			(effects
				(font
					(size 1.27 1.27)
				)
				(justify left)
			)
		)
	)
	(global_label "CSI2_D0_P"
		(shape input)
		(at 278.13 78.74 0)
		(effects
			(font
				(size 1.27 1.27)
			)
			(justify left)
		)
		(property "Intersheetrefs" "${INTERSHEET_REFS}"
			(at 293.3096 78.74 0)
			(effects
				(font
					(size 1.27 1.27)
				)
				(justify left)
			)
		)
	)
	(global_label "I2S0_SCLK"
		(shape output)
		(at 194.31 125.73 0)
		(effects
			(font
				(size 1.27 1.27)
			)
			(justify left)
		)
		(property "Intersheetrefs" "${INTERSHEET_REFS}"
			(at 208.28 125.73 0)
			(effects
				(font
					(size 1.27 1.27)
				)
				(justify left)
			)
		)
	)
	(global_label "CSI0_D1_P"
		(shape input)
		(at 278.13 48.26 0)
		(effects
			(font
				(size 1.27 1.27)
			)
			(justify left)
		)
		(property "Intersheetrefs" "${INTERSHEET_REFS}"
			(at 293.3096 48.26 0)
			(effects
				(font
					(size 1.27 1.27)
				)
				(justify left)
			)
		)
	)
	(global_label "DP1_HDMI_AUX_N"
		(shape output)
		(at 283.21 199.39 0)
		(fields_autoplaced yes)
		(effects
			(font
				(size 1.27 1.27)
			)
			(justify left)
		)
		(property "Intersheetrefs" "${INTERSHEET_REFS}"
			(at 301.8912 199.3106 0)
			(effects
				(font
					(size 1.27 1.27)
				)
				(justify left)
			)
		)
	)
	(global_label "GBE_MDI3_P"
		(shape input)
		(at 377.19 240.03 0)
		(fields_autoplaced yes)
		(effects
			(font
				(size 1.27 1.27)
			)
			(justify left)
		)
		(property "Intersheetrefs" "${INTERSHEET_REFS}"
			(at 394.335 240.03 0)
			(effects
				(font
					(size 1.27 1.27)
				)
				(justify left)
			)
		)
	)
	(global_label "USER_LED1"
		(shape output)
		(at 91.44 36.83 0)
		(effects
			(font
				(size 1.27 1.27)
			)
			(justify left)
		)
		(property "Intersheetrefs" "${INTERSHEET_REFS}"
			(at 106.045 36.83 0)
			(effects
				(font
					(size 1.27 1.27)
				)
				(justify left)
			)
		)
	)
	(global_label "~{GPIO_INT}"
		(shape input)
		(at 91.44 31.75 0)
		(effects
			(font
				(size 1.27 1.27)
			)
			(justify left)
		)
		(property "Intersheetrefs" "${INTERSHEET_REFS}"
			(at 106.045 31.75 0)
			(effects
				(font
					(size 1.27 1.27)
				)
				(justify left)
			)
		)
	)
	(global_label "I2C2_SDA"
		(shape bidirectional)
		(at 194.31 88.9 0)
		(effects
			(font
				(size 1.27 1.27)
			)
			(justify left)
		)
		(property "Intersheetrefs" "${INTERSHEET_REFS}"
			(at 208.28 88.9 0)
			(effects
				(font
					(size 1.27 1.27)
				)
				(justify left)
			)
		)
	)
	(global_label "MODULE_ID"
		(shape output)
		(at 110.49 133.35 0)
		(effects
			(font
				(size 1.27 1.27)
			)
			(justify left)
		)
		(property "Intersheetrefs" "${INTERSHEET_REFS}"
			(at 128.27 133.35 0)
			(effects
				(font
					(size 1.27 1.27)
				)
				(justify left)
			)
		)
	)
	(global_label "PCIE2_TX1_N"
		(shape bidirectional)
		(at 375.92 163.83 0)
		(effects
			(font
				(size 1.27 1.27)
			)
			(justify left)
		)
		(property "Intersheetrefs" "${INTERSHEET_REFS}"
			(at 394.335 163.83 0)
			(effects
				(font
					(size 1.27 1.27)
				)
				(justify left)
			)
		)
	)
	(global_label "SYS_SCL"
		(shape output)
		(at 194.31 72.39 0)
		(effects
			(font
				(size 1.27 1.27)
			)
			(justify left)
		)
		(property "Intersheetrefs" "${INTERSHEET_REFS}"
			(at 207.645 72.39 0)
			(effects
				(font
					(size 1.27 1.27)
				)
				(justify left)
			)
		)
	)
	(global_label "I2S1_SCLK"
		(shape output)
		(at 194.31 138.43 0)
		(effects
			(font
				(size 1.27 1.27)
			)
			(justify left)
		)
		(property "Intersheetrefs" "${INTERSHEET_REFS}"
			(at 208.28 138.43 0)
			(effects
				(font
					(size 1.27 1.27)
				)
				(justify left)
			)
		)
	)
	(global_label "USBSS2_TX_N"
		(shape output)
		(at 194.31 222.25 0)
		(effects
			(font
				(size 1.27 1.27)
			)
			(justify left)
		)
		(property "Intersheetrefs" "${INTERSHEET_REFS}"
			(at 210.185 222.25 0)
			(effects
				(font
					(size 1.1 1.1)
				)
				(justify left)
			)
		)
	)
	(global_label "VSYNC_CAM2"
		(shape output)
		(at 91.44 60.96 0)
		(effects
			(font
				(size 1.27 1.27)
			)
			(justify left)
		)
		(property "Intersheetrefs" "${INTERSHEET_REFS}"
			(at 106.68 60.96 0)
			(effects
				(font
					(size 1.27 1.27)
				)
				(justify left)
			)
		)
	)
	(global_label "CSI0_CLK_P"
		(shape input)
		(at 278.13 38.1 0)
		(effects
			(font
				(size 1.27 1.27)
			)
			(justify left)
		)
		(property "Intersheetrefs" "${INTERSHEET_REFS}"
			(at 293.37 38.1 0)
			(effects
				(font
					(size 1.27 1.27)
				)
				(justify left)
			)
		)
	)
	(global_label "USER_BTN1"
		(shape input)
		(at 91.44 41.91 0)
		(effects
			(font
				(size 1.27 1.27)
			)
			(justify left)
		)
		(property "Intersheetrefs" "${INTERSHEET_REFS}"
			(at 106.045 41.91 0)
			(effects
				(font
					(size 1.27 1.27)
				)
				(justify left)
			)
		)
	)
	(global_label "VSYNC_CAM1"
		(shape output)
		(at 295.91 111.76 0)
		(effects
			(font
				(size 1.27 1.27)
			)
			(justify left)
		)
		(property "Intersheetrefs" "${INTERSHEET_REFS}"
			(at 311.15 111.76 0)
			(effects
				(font
					(size 1.27 1.27)
				)
				(justify left)
			)
		)
	)
	(global_label "I2S1_LRCK"
		(shape output)
		(at 194.31 146.05 0)
		(effects
			(font
				(size 1.27 1.27)
			)
			(justify left)
		)
		(property "Intersheetrefs" "${INTERSHEET_REFS}"
			(at 208.28 146.05 0)
			(effects
				(font
					(size 1.27 1.27)
				)
				(justify left)
			)
		)
	)
	(global_label "UART0_TXD"
		(shape output)
		(at 195.58 44.45 0)
		(effects
			(font
				(size 1.27 1.27)
			)
			(justify left)
		)
		(property "Intersheetrefs" "${INTERSHEET_REFS}"
			(at 209.55 44.45 0)
			(effects
				(font
					(size 1.27 1.27)
				)
				(justify left)
			)
		)
	)
	(global_label "PCIE1_CLKREQ*"
		(shape bidirectional)
		(at 375.92 102.87 0)
		(effects
			(font
				(size 1.27 1.27)
			)
			(justify left)
		)
		(property "Intersheetrefs" "${INTERSHEET_REFS}"
			(at 394.3593 102.7906 0)
			(effects
				(font
					(size 1.27 1.27)
				)
				(justify left)
			)
		)
	)
	(global_label "PCIE0_TX1_N"
		(shape bidirectional)
		(at 375.92 68.58 0)
		(effects
			(font
				(size 1.27 1.27)
			)
			(justify left)
		)
		(property "Intersheetrefs" "${INTERSHEET_REFS}"
			(at 394.335 68.58 0)
			(effects
				(font
					(size 1.27 1.27)
				)
				(justify left)
			)
		)
	)
	(global_label "CSI0_D0_P"
		(shape input)
		(at 278.13 43.18 0)
		(effects
			(font
				(size 1.27 1.27)
			)
			(justify left)
		)
		(property "Intersheetrefs" "${INTERSHEET_REFS}"
			(at 293.3096 43.18 0)
			(effects
				(font
					(size 1.27 1.27)
				)
				(justify left)
			)
		)
	)
	(global_label "DP1_TXD0_HDMI_TX2_P"
		(shape output)
		(at 283.21 203.2 0)
		(fields_autoplaced yes)
		(effects
			(font
				(size 1.27 1.27)
			)
			(justify left)
		)
		(property "Intersheetrefs" "${INTERSHEET_REFS}"
			(at 307.2131 203.1206 0)
			(effects
				(font
					(size 1.27 1.27)
				)
				(justify left)
			)
		)
	)
	(global_label "GBE_MDI2_P"
		(shape input)
		(at 377.19 233.68 0)
		(fields_autoplaced yes)
		(effects
			(font
				(size 1.27 1.27)
			)
			(justify left)
		)
		(property "Intersheetrefs" "${INTERSHEET_REFS}"
			(at 394.335 233.68 0)
			(effects
				(font
					(size 1.27 1.27)
				)
				(justify left)
			)
		)
	)
	(global_label "PCIE2_CLK_N"
		(shape bidirectional)
		(at 375.92 133.35 0)
		(effects
			(font
				(size 1.27 1.27)
			)
			(justify left)
		)
		(property "Intersheetrefs" "${INTERSHEET_REFS}"
			(at 394.335 133.35 0)
			(effects
				(font
					(size 1.27 1.27)
				)
				(justify left)
			)
		)
	)
	(global_label "GBE_MDI1_N"
		(shape input)
		(at 377.19 229.87 0)
		(fields_autoplaced yes)
		(effects
			(font
				(size 1.27 1.27)
			)
			(justify left)
		)
		(property "Intersheetrefs" "${INTERSHEET_REFS}"
			(at 394.335 229.87 0)
			(effects
				(font
					(size 1.27 1.27)
				)
				(justify left)
			)
		)
	)
	(global_label "CSI2_D1_N"
		(shape input)
		(at 278.13 86.36 0)
		(effects
			(font
				(size 1.27 1.27)
			)
			(justify left)
		)
		(property "Intersheetrefs" "${INTERSHEET_REFS}"
			(at 293.37 86.36 0)
			(effects
				(font
					(size 1.27 1.27)
				)
				(justify left)
			)
		)
	)
	(global_label "FAN_TACH"
		(shape input)
		(at 110.49 137.16 0)
		(effects
			(font
				(size 1.27 1.27)
			)
			(justify left)
		)
		(property "Intersheetrefs" "${INTERSHEET_REFS}"
			(at 128.27 137.16 0)
			(effects
				(font
					(size 1.27 1.27)
				)
				(justify left)
			)
		)
	)
	(global_label "PCIE1_RX0_P"
		(shape bidirectional)
		(at 375.92 118.11 0)
		(effects
			(font
				(size 1.27 1.27)
			)
			(justify left)
		)
		(property "Intersheetrefs" "${INTERSHEET_REFS}"
			(at 398.78 118.11 0)
			(effects
				(font
					(size 1.27 1.27)
				)
				(justify right)
			)
		)
	)
	(global_label "~{RESET}"
		(shape bidirectional)
		(at 110.49 149.86 0)
		(effects
			(font
				(size 1.27 1.27)
			)
			(justify left)
		)
		(property "Intersheetrefs" "${INTERSHEET_REFS}"
			(at 128.27 149.86 0)
			(effects
				(font
					(size 1.27 1.27)
				)
				(justify left)
			)
		)
	)
	(global_label "PCIE0_RX1_N"
		(shape bidirectional)
		(at 375.92 73.66 0)
		(effects
			(font
				(size 1.27 1.27)
			)
			(justify left)
		)
		(property "Intersheetrefs" "${INTERSHEET_REFS}"
			(at 394.335 73.66 0)
			(effects
				(font
					(size 1.27 1.27)
				)
				(justify left)
			)
		)
	)
	(global_label "PCIE0_RX1_P"
		(shape bidirectional)
		(at 375.92 71.12 0)
		(effects
			(font
				(size 1.27 1.27)
			)
			(justify left)
		)
		(property "Intersheetrefs" "${INTERSHEET_REFS}"
			(at 394.335 71.12 0)
			(effects
				(font
					(size 1.27 1.27)
				)
				(justify left)
			)
		)
	)
	(global_label "CSI2_D0_N"
		(shape input)
		(at 278.13 81.28 0)
		(effects
			(font
				(size 1.27 1.27)
			)
			(justify left)
		)
		(property "Intersheetrefs" "${INTERSHEET_REFS}"
			(at 293.37 81.28 0)
			(effects
				(font
					(size 1.27 1.27)
				)
				(justify left)
			)
		)
	)
	(global_label "GBE_MDI1_P"
		(shape input)
		(at 377.19 227.33 0)
		(fields_autoplaced yes)
		(effects
			(font
				(size 1.27 1.27)
			)
			(justify left)
		)
		(property "Intersheetrefs" "${INTERSHEET_REFS}"
			(at 394.335 227.33 0)
			(effects
				(font
					(size 1.27 1.27)
				)
				(justify left)
			)
		)
	)
	(global_label "DEBUG_TXD"
		(shape output)
		(at 88.9 255.27 0)
		(effects
			(font
				(size 1.27 1.27)
			)
			(justify left)
		)
		(property "Intersheetrefs" "${INTERSHEET_REFS}"
			(at 102.87 255.27 0)
			(effects
				(font
					(size 1.27 1.27)
				)
				(justify left)
			)
		)
	)
	(global_label "GPIO010"
		(shape input)
		(at 116.84 49.53 0)
		(effects
			(font
				(size 1.27 1.27)
			)
			(justify left)
		)
		(property "Intersheetrefs" "${INTERSHEET_REFS}"
			(at 127.635 49.53 0)
			(effects
				(font
					(size 1.27 1.27)
				)
				(justify left)
			)
		)
	)
	(global_label "PCIE1_RST*"
		(shape bidirectional)
		(at 375.92 100.33 0)
		(effects
			(font
				(size 1.27 1.27)
			)
			(justify left)
		)
		(property "Intersheetrefs" "${INTERSHEET_REFS}"
			(at 394.335 100.33 0)
			(effects
				(font
					(size 1.27 1.27)
				)
				(justify left)
			)
		)
	)
	(global_label "CSI3_CLK_P"
		(shape input)
		(at 278.13 90.17 0)
		(effects
			(font
				(size 1.27 1.27)
			)
			(justify left)
		)
		(property "Intersheetrefs" "${INTERSHEET_REFS}"
			(at 293.37 90.17 0)
			(effects
				(font
					(size 1.27 1.27)
				)
				(justify left)
			)
		)
	)
	(global_label "PCIE1_RX0_N"
		(shape bidirectional)
		(at 375.92 120.65 0)
		(effects
			(font
				(size 1.27 1.27)
			)
			(justify left)
		)
		(property "Intersheetrefs" "${INTERSHEET_REFS}"
			(at 398.78 120.65 0)
			(effects
				(font
					(size 1.27 1.27)
				)
				(justify right)
			)
		)
	)
	(global_label "CSI3_CLK_N"
		(shape input)
		(at 278.13 92.71 0)
		(effects
			(font
				(size 1.27 1.27)
			)
			(justify left)
		)
		(property "Intersheetrefs" "${INTERSHEET_REFS}"
			(at 293.4305 92.71 0)
			(effects
				(font
					(size 1.27 1.27)
				)
				(justify left)
			)
		)
	)
	(global_label "SCL_CAM"
		(shape output)
		(at 279.4 121.92 0)
		(effects
			(font
				(size 1.27 1.27)
			)
			(justify left)
		)
		(property "Intersheetrefs" "${INTERSHEET_REFS}"
			(at 294.5795 121.92 0)
			(effects
				(font
					(size 1.27 1.27)
				)
				(justify left)
			)
		)
	)
	(global_label "PCIE1_TX0_N"
		(shape bidirectional)
		(at 375.92 115.57 0)
		(effects
			(font
				(size 1.27 1.27)
			)
			(justify left)
		)
		(property "Intersheetrefs" "${INTERSHEET_REFS}"
			(at 398.78 115.57 0)
			(effects
				(font
					(size 1.27 1.27)
				)
				(justify right)
			)
		)
	)
	(global_label "PCIE1_TX0_P"
		(shape bidirectional)
		(at 375.92 113.03 0)
		(effects
			(font
				(size 1.27 1.27)
			)
			(justify left)
		)
		(property "Intersheetrefs" "${INTERSHEET_REFS}"
			(at 398.78 113.03 0)
			(effects
				(font
					(size 1.27 1.27)
				)
				(justify right)
			)
		)
	)
	(global_label "USBSS0_RX_N"
		(shape output)
		(at 194.31 200.66 0)
		(effects
			(font
				(size 1.27 1.27)
			)
			(justify left)
		)
		(property "Intersheetrefs" "${INTERSHEET_REFS}"
			(at 210.185 200.66 0)
			(effects
				(font
					(size 1.1 1.1)
				)
				(justify left)
			)
		)
	)
	(global_label "USBSS1_TX_P"
		(shape output)
		(at 194.31 205.74 0)
		(effects
			(font
				(size 1.27 1.27)
			)
			(justify left)
		)
		(property "Intersheetrefs" "${INTERSHEET_REFS}"
			(at 210.185 205.74 0)
			(effects
				(font
					(size 1.1 1.1)
				)
				(justify left)
			)
		)
	)
	(global_label "CSI1_CLK_P"
		(shape input)
		(at 278.13 55.88 0)
		(effects
			(font
				(size 1.27 1.27)
			)
			(justify left)
		)
		(property "Intersheetrefs" "${INTERSHEET_REFS}"
			(at 293.37 55.88 0)
			(effects
				(font
					(size 1.27 1.27)
				)
				(justify left)
			)
		)
	)
	(global_label "PCIE2_TX0_P"
		(shape bidirectional)
		(at 375.92 137.16 0)
		(effects
			(font
				(size 1.27 1.27)
			)
			(justify left)
		)
		(property "Intersheetrefs" "${INTERSHEET_REFS}"
			(at 394.335 137.16 0)
			(effects
				(font
					(size 1.27 1.27)
				)
				(justify left)
			)
		)
	)
	(global_label "GPIO13"
		(shape bidirectional)
		(at 91.44 57.15 0)
		(effects
			(font
				(size 1.27 1.27)
			)
			(justify left)
		)
		(property "Intersheetrefs" "${INTERSHEET_REFS}"
			(at 106.045 57.15 0)
			(effects
				(font
					(size 1.27 1.27)
				)
				(justify left)
			)
		)
	)
	(global_label "DEBUG_RXD"
		(shape input)
		(at 88.9 252.73 0)
		(effects
			(font
				(size 1.27 1.27)
			)
			(justify left)
		)
		(property "Intersheetrefs" "${INTERSHEET_REFS}"
			(at 102.87 252.73 0)
			(effects
				(font
					(size 1.27 1.27)
				)
				(justify left)
			)
		)
	)
	(global_label "PCIE3_CLK_N"
		(shape bidirectional)
		(at 375.92 157.48 0)
		(effects
			(font
				(size 1.27 1.27)
			)
			(justify left)
		)
		(property "Intersheetrefs" "${INTERSHEET_REFS}"
			(at 394.335 157.48 0)
			(effects
				(font
					(size 1.27 1.27)
				)
				(justify left)
			)
		)
	)
	(global_label "CSI2_CLK_P"
		(shape input)
		(at 278.13 73.66 0)
		(effects
			(font
				(size 1.27 1.27)
			)
			(justify left)
		)
		(property "Intersheetrefs" "${INTERSHEET_REFS}"
			(at 293.37 73.66 0)
			(effects
				(font
					(size 1.27 1.27)
				)
				(justify left)
			)
		)
	)
	(global_label "DP1_TXD1_HDMI_TX1_P"
		(shape output)
		(at 283.21 209.55 0)
		(fields_autoplaced yes)
		(effects
			(font
				(size 1.27 1.27)
			)
			(justify left)
		)
		(property "Intersheetrefs" "${INTERSHEET_REFS}"
			(at 307.2131 209.4706 0)
			(effects
				(font
					(size 1.27 1.27)
				)
				(justify left)
			)
		)
	)
	(global_label "GPIO09"
		(shape bidirectional)
		(at 91.44 46.99 0)
		(effects
			(font
				(size 1.27 1.27)
			)
			(justify left)
		)
		(property "Intersheetrefs" "${INTERSHEET_REFS}"
			(at 106.045 46.99 0)
			(effects
				(font
					(size 1.27 1.27)
				)
				(justify left)
			)
		)
	)
	(global_label "SPIO_SCK"
		(shape output)
		(at 194.31 95.25 0)
		(effects
			(font
				(size 1.27 1.27)
			)
			(justify left)
		)
		(property "Intersheetrefs" "${INTERSHEET_REFS}"
			(at 208.28 95.25 0)
			(effects
				(font
					(size 1.27 1.27)
				)
				(justify left)
			)
		)
	)
	(global_label "USBSS0_TX_N"
		(shape output)
		(at 194.31 194.31 0)
		(effects
			(font
				(size 1.27 1.27)
			)
			(justify left)
		)
		(property "Intersheetrefs" "${INTERSHEET_REFS}"
			(at 210.185 194.31 0)
			(effects
				(font
					(size 1.1 1.1)
				)
				(justify left)
			)
		)
	)
	(global_label "CSI0_D1_N"
		(shape input)
		(at 278.13 50.8 0)
		(effects
			(font
				(size 1.27 1.27)
			)
			(justify left)
		)
		(property "Intersheetrefs" "${INTERSHEET_REFS}"
			(at 293.37 50.8 0)
			(effects
				(font
					(size 1.27 1.27)
				)
				(justify left)
			)
		)
	)
	(global_label "I2S0_SDOUT"
		(shape output)
		(at 194.31 128.27 0)
		(effects
			(font
				(size 1.27 1.27)
			)
			(justify left)
		)
		(property "Intersheetrefs" "${INTERSHEET_REFS}"
			(at 208.28 128.27 0)
			(effects
				(font
					(size 1.27 1.27)
				)
				(justify left)
			)
		)
	)
	(global_label "UART1_RXD"
		(shape input)
		(at 195.58 59.69 0)
		(effects
			(font
				(size 1.27 1.27)
			)
			(justify left)
		)
		(property "Intersheetrefs" "${INTERSHEET_REFS}"
			(at 209.55 59.69 0)
			(effects
				(font
					(size 1.27 1.27)
				)
				(justify left)
			)
		)
	)
	(global_label "3V3_STDB"
		(shape input)
		(at 16.51 143.51 90)
		(fields_autoplaced yes)
		(effects
			(font
				(size 1.27 1.27)
			)
			(justify left)
		)
		(property "Intersheetrefs" "${INTERSHEET_REFS}"
			(at 16.51 131.3325 90)
			(effects
				(font
					(size 1.27 1.27)
				)
				(justify left)
			)
		)
	)
	(global_label "SPI1_MOSI"
		(shape output)
		(at 194.31 113.03 0)
		(effects
			(font
				(size 1.27 1.27)
			)
			(justify left)
		)
		(property "Intersheetrefs" "${INTERSHEET_REFS}"
			(at 208.28 113.03 0)
			(effects
				(font
					(size 1.27 1.27)
				)
				(justify left)
			)
		)
	)
	(global_label "PCIE0_TX1_P"
		(shape bidirectional)
		(at 375.92 66.04 0)
		(effects
			(font
				(size 1.27 1.27)
			)
			(justify left)
		)
		(property "Intersheetrefs" "${INTERSHEET_REFS}"
			(at 394.335 66.04 0)
			(effects
				(font
					(size 1.27 1.27)
				)
				(justify left)
			)
		)
	)
	(global_label "PCIE0_TX2_N"
		(shape bidirectional)
		(at 375.92 80.01 0)
		(effects
			(font
				(size 1.27 1.27)
			)
			(justify left)
		)
		(property "Intersheetrefs" "${INTERSHEET_REFS}"
			(at 394.335 80.01 0)
			(effects
				(font
					(size 1.27 1.27)
				)
				(justify left)
			)
		)
	)
	(global_label "SPI1_MISO"
		(shape input)
		(at 194.31 115.57 0)
		(effects
			(font
				(size 1.27 1.27)
			)
			(justify left)
		)
		(property "Intersheetrefs" "${INTERSHEET_REFS}"
			(at 208.28 115.57 0)
			(effects
				(font
					(size 1.27 1.27)
				)
				(justify left)
			)
		)
	)
	(global_label "DP1_TXD3_HDMI_TXC_N"
		(shape output)
		(at 283.21 224.79 0)
		(fields_autoplaced yes)
		(effects
			(font
				(size 1.27 1.27)
			)
			(justify left)
		)
		(property "Intersheetrefs" "${INTERSHEET_REFS}"
			(at 307.3341 224.7106 0)
			(effects
				(font
					(size 1.27 1.27)
				)
				(justify left)
			)
		)
	)
	(global_label "CSI3_D1_N"
		(shape input)
		(at 278.13 102.87 0)
		(effects
			(font
				(size 1.27 1.27)
			)
			(justify left)
		)
		(property "Intersheetrefs" "${INTERSHEET_REFS}"
			(at 293.37 102.87 0)
			(effects
				(font
					(size 1.27 1.27)
				)
				(justify left)
			)
		)
	)
	(global_label "PCIE1_CLK_N"
		(shape bidirectional)
		(at 375.92 109.22 0)
		(effects
			(font
				(size 1.27 1.27)
			)
			(justify left)
		)
		(property "Intersheetrefs" "${INTERSHEET_REFS}"
			(at 394.3954 109.22 0)
			(effects
				(font
					(size 1.27 1.27)
				)
				(justify left)
			)
		)
	)
	(global_label "GBE_MDI0_N"
		(shape input)
		(at 377.19 223.52 0)
		(fields_autoplaced yes)
		(effects
			(font
				(size 1.27 1.27)
			)
			(justify left)
		)
		(property "Intersheetrefs" "${INTERSHEET_REFS}"
			(at 394.335 223.52 0)
			(effects
				(font
					(size 1.27 1.27)
				)
				(justify left)
			)
		)
	)
	(global_label "PCIE0_TX3_P"
		(shape bidirectional)
		(at 375.92 88.9 0)
		(effects
			(font
				(size 1.27 1.27)
			)
			(justify left)
		)
		(property "Intersheetrefs" "${INTERSHEET_REFS}"
			(at 394.335 88.9 0)
			(effects
				(font
					(size 1.27 1.27)
				)
				(justify left)
			)
		)
	)
	(global_label "CAN_TX"
		(shape output)
		(at 194.31 153.67 0)
		(effects
			(font
				(size 1.27 1.27)
			)
			(justify left)
		)
		(property "Intersheetrefs" "${INTERSHEET_REFS}"
			(at 207.01 153.67 0)
			(effects
				(font
					(size 1.27 1.27)
				)
				(justify left)
			)
		)
	)
	(global_label "PCIE2_TX0_N"
		(shape bidirectional)
		(at 375.92 139.7 0)
		(effects
			(font
				(size 1.27 1.27)
			)
			(justify left)
		)
		(property "Intersheetrefs" "${INTERSHEET_REFS}"
			(at 394.335 139.7 0)
			(effects
				(font
					(size 1.27 1.27)
				)
				(justify left)
			)
		)
	)
	(global_label "CSI1_D1_P"
		(shape input)
		(at 278.13 66.04 0)
		(effects
			(font
				(size 1.27 1.27)
			)
			(justify left)
		)
		(property "Intersheetrefs" "${INTERSHEET_REFS}"
			(at 293.3096 66.04 0)
			(effects
				(font
					(size 1.27 1.27)
				)
				(justify left)
			)
		)
	)
	(global_label "USBSS2_RX_N"
		(shape output)
		(at 194.31 228.6 0)
		(effects
			(font
				(size 1.27 1.27)
			)
			(justify left)
		)
		(property "Intersheetrefs" "${INTERSHEET_REFS}"
			(at 210.185 228.6 0)
			(effects
				(font
					(size 1.1 1.1)
				)
				(justify left)
			)
		)
	)
	(global_label "GPIO11"
		(shape bidirectional)
		(at 91.44 52.07 0)
		(effects
			(font
				(size 1.27 1.27)
			)
			(justify left)
		)
		(property "Intersheetrefs" "${INTERSHEET_REFS}"
			(at 106.045 52.07 0)
			(effects
				(font
					(size 1.27 1.27)
				)
				(justify left)
			)
		)
	)
	(global_label "PCIE_WAKE*"
		(shape bidirectional)
		(at 375.92 38.1 0)
		(effects
			(font
				(size 1.27 1.27)
			)
			(justify left)
		)
		(property "Intersheetrefs" "${INTERSHEET_REFS}"
			(at 394.335 38.1 0)
			(effects
				(font
					(size 1.27 1.27)
				)
				(justify left)
			)
		)
	)
	(global_label "I2S1_SDIN"
		(shape input)
		(at 194.31 143.51 0)
		(effects
			(font
				(size 1.27 1.27)
			)
			(justify left)
		)
		(property "Intersheetrefs" "${INTERSHEET_REFS}"
			(at 208.28 143.51 0)
			(effects
				(font
					(size 1.27 1.27)
				)
				(justify left)
			)
		)
	)
	(global_label "PCIE0_CLK_P"
		(shape bidirectional)
		(at 375.92 48.26 0)
		(effects
			(font
				(size 1.27 1.27)
			)
			(justify left)
		)
		(property "Intersheetrefs" "${INTERSHEET_REFS}"
			(at 394.335 48.895 0)
			(effects
				(font
					(size 1.27 1.27)
				)
				(justify left)
			)
		)
	)
	(symbol
		(lib_id "antmicroTestPoints:TP_0.75mm_SMD")
		(at 283.21 189.23 0)
		(unit 1)
		(exclude_from_sim no)
		(in_bom no)
		(on_board yes)
		(dnp no)
		(property "Reference" "TP35"
			(at 287.02 189.23 0)
			(effects
				(font
					(size 1.27 1.27)
				)
				(justify left)
			)
		)
		(property "Value" "TP_0.75mm_SMD"
			(at 293.37 193.04 0)
			(effects
				(font
					(size 1.27 1.27)
					(thickness 0.15)
				)
				(justify left bottom)
				(hide yes)
			)
		)
		(property "Footprint" "antmicro-footprints:TP_SMD_0.75mm"
			(at 293.37 195.58 0)
			(effects
				(font
					(size 1.27 1.27)
					(thickness 0.15)
				)
				(justify left bottom)
				(hide yes)
			)
		)
		(property "Datasheet" ""
			(at 300.99 201.93 0)
			(effects
				(font
					(size 1.27 1.27)
					(thickness 0.15)
				)
				(justify left bottom)
				(hide yes)
			)
		)
		(property "Description" ""
			(at 283.21 189.23 0)
			(effects
				(font
					(size 1.27 1.27)
				)
				(hide yes)
			)
		)
		(property "MPN" ""
			(at 294.005 200.66 0)
			(effects
				(font
					(size 1.27 1.27)
					(thickness 0.15)
				)
				(justify left bottom)
				(hide yes)
			)
		)
		(property "Manufacturer" ""
			(at 294.005 195.58 0)
			(effects
				(font
					(size 1.27 1.27)
					(thickness 0.15)
				)
				(justify left bottom)
				(hide yes)
			)
		)
		(property "Author" "Antmicro"
			(at 293.37 198.12 0)
			(effects
				(font
					(size 1.27 1.27)
					(thickness 0.15)
				)
				(justify left bottom)
				(hide yes)
			)
		)
		(property "License" "Apache-2.0"
			(at 293.37 200.66 0)
			(effects
				(font
					(size 1.27 1.27)
					(thickness 0.15)
				)
				(justify left bottom)
				(hide yes)
			)
		)
		(pin "1"
		)
		(instances
			(project "jetson-orin-baseboard"
				(path ""
					(reference "TP35")
					(unit 1)
				)
			)
		)
	)
	(symbol
		(lib_id "antmicroSoMConnectors:Bus_DDR4_SODIMM_CUSTOM_Jetson-Orin-H9.2mm-socket")
		(at 278.13 189.23 0)
		(mirror y)
		(unit 5)
		(exclude_from_sim no)
		(in_bom yes)
		(on_board yes)
		(dnp no)
		(fields_autoplaced yes)
		(property "Reference" "J15"
			(at 258.445 181.61 0)
			(effects
				(font
					(size 1.27 1.27)
					(thickness 0.15)
				)
			)
		)
		(property "Value" "Bus_DDR4_SODIMM_CUSTOM_Jetson-Orin-H9.2mm-socket"
			(at 215.9 196.85 0)
			(effects
				(font
					(size 1.27 1.27)
					(thickness 0.15)
				)
				(justify left bottom)
				(hide yes)
			)
		)
		(property "Footprint" "antmicro-footprints:TE_2309413"
			(at 215.9 199.39 0)
			(effects
				(font
					(size 1.27 1.27)
					(thickness 0.15)
				)
				(justify left bottom)
				(hide yes)
			)
		)
		(property "Datasheet" "https://developer.nvidia.com/jetson-orin-nx-series-data-sheet"
			(at 215.9 201.93 0)
			(effects
				(font
					(size 1.27 1.27)
					(thickness 0.15)
				)
				(justify left bottom)
				(hide yes)
			)
		)
		(property "Description" ""
			(at 278.13 189.23 0)
			(effects
				(font
					(size 1.27 1.27)
				)
				(hide yes)
			)
		)
		(property "Manufacturer" "TE Connectivity"
			(at 215.9 204.47 0)
			(effects
				(font
					(size 1.27 1.27)
					(thickness 0.15)
				)
				(justify left bottom)
				(hide yes)
			)
		)
		(property "MPN" "2309413-1"
			(at 258.445 184.15 0)
			(effects
				(font
					(size 1.27 1.27)
					(thickness 0.15)
				)
			)
		)
		(property "License" "Apache-2.0"
			(at 215.9 209.55 0)
			(effects
				(font
					(size 1.27 1.27)
					(thickness 0.15)
				)
				(justify left bottom)
				(hide yes)
			)
		)
		(property "Author" "Antmicro"
			(at 215.9 212.09 0)
			(effects
				(font
					(size 1.27 1.27)
					(thickness 0.15)
				)
				(justify left bottom)
				(hide yes)
			)
		)
		(pin "245"
		)
		(pin "227"
		)
		(pin "229"
		)
		(pin "158"
		)
		(pin "184"
		)
		(pin "186"
		)
		(pin "248"
		)
		(pin "25"
		)
		(pin "16"
		)
		(pin "250"
		)
		(pin "35"
		)
		(pin "142"
		)
		(pin "148"
		)
		(pin "133"
		)
		(pin "134"
		)
		(pin "77"
		)
		(pin "81"
		)
		(pin "136"
		)
		(pin "137"
		)
		(pin "207"
		)
		(pin "168"
		)
		(pin "39"
		)
		(pin "36"
		)
		(pin "65"
		)
		(pin "69"
		)
		(pin "21"
		)
		(pin "209"
		)
		(pin "139"
		)
		(pin "140"
		)
		(pin "205"
		)
		(pin "182"
		)
		(pin "183"
		)
		(pin "107"
		)
		(pin "72"
		)
		(pin "84"
		)
		(pin "212"
		)
		(pin "216"
		)
		(pin "114"
		)
		(pin "50"
		)
		(pin "199"
		)
		(pin "68"
		)
		(pin "37"
		)
		(pin "31"
		)
		(pin "74"
		)
		(pin "252"
		)
		(pin "7"
		)
		(pin "197"
		)
		(pin "53"
		)
		(pin "57"
		)
		(pin "202"
		)
		(pin "204"
		)
		(pin "261"
		)
		(pin "100"
		)
		(pin "63"
		)
		(pin "15"
		)
		(pin "17"
		)
		(pin "6"
		)
		(pin "201"
		)
		(pin "169"
		)
		(pin "172"
		)
		(pin "4"
		)
		(pin "2"
		)
		(pin "159"
		)
		(pin "43"
		)
		(pin "70"
		)
		(pin "141"
		)
		(pin "3"
		)
		(pin "29"
		)
		(pin "233"
		)
		(pin "164"
		)
		(pin "147"
		)
		(pin "10"
		)
		(pin "219"
		)
		(pin "221"
		)
		(pin "40"
		)
		(pin "42"
		)
		(pin "223"
		)
		(pin "225"
		)
		(pin "120"
		)
		(pin "122"
		)
		(pin "73"
		)
		(pin "117"
		)
		(pin "121"
		)
		(pin "12"
		)
		(pin "83"
		)
		(pin "88"
		)
		(pin "99"
		)
		(pin "109"
		)
		(pin "64"
		)
		(pin "66"
		)
		(pin "188"
		)
		(pin "190"
		)
		(pin "192"
		)
		(pin "194"
		)
		(pin "59"
		)
		(pin "87"
		)
		(pin "251"
		)
		(pin "90"
		)
		(pin "92"
		)
		(pin "71"
		)
		(pin "75"
		)
		(pin "119"
		)
		(pin "126"
		)
		(pin "127"
		)
		(pin "1"
		)
		(pin "102"
		)
		(pin "52"
		)
		(pin "54"
		)
		(pin "19"
		)
		(pin "253"
		)
		(pin "260"
		)
		(pin "230"
		)
		(pin "151"
		)
		(pin "154"
		)
		(pin "247"
		)
		(pin "67"
		)
		(pin "243"
		)
		(pin "155"
		)
		(pin "156"
		)
		(pin "20"
		)
		(pin "208"
		)
		(pin "242"
		)
		(pin "231"
		)
		(pin "14"
		)
		(pin "241"
		)
		(pin "78"
		)
		(pin "132"
		)
		(pin "18"
		)
		(pin "240"
		)
		(pin "171"
		)
		(pin "170"
		)
		(pin "153"
		)
		(pin "49"
		)
		(pin "178"
		)
		(pin "226"
		)
		(pin "232"
		)
		(pin "176"
		)
		(pin "185"
		)
		(pin "9"
		)
		(pin "152"
		)
		(pin "101"
		)
		(pin "143"
		)
		(pin "165"
		)
		(pin "257"
		)
		(pin "103"
		)
		(pin "85"
		)
		(pin "259"
		)
		(pin "104"
		)
		(pin "146"
		)
		(pin "220"
		)
		(pin "246"
		)
		(pin "180"
		)
		(pin "181"
		)
		(pin "105"
		)
		(pin "210"
		)
		(pin "254"
		)
		(pin "256"
		)
		(pin "118"
		)
		(pin "124"
		)
		(pin "217"
		)
		(pin "214"
		)
		(pin "255"
		)
		(pin "30"
		)
		(pin "111"
		)
		(pin "115"
		)
		(pin "258"
		)
		(pin "213"
		)
		(pin "82"
		)
		(pin "129"
		)
		(pin "144"
		)
		(pin "128"
		)
		(pin "130"
		)
		(pin "61"
		)
		(pin "79"
		)
		(pin "26"
		)
		(pin "215"
		)
		(pin "33"
		)
		(pin "13"
		)
		(pin "22"
		)
		(pin "62"
		)
		(pin "113"
		)
		(pin "187"
		)
		(pin "177"
		)
		(pin "125"
		)
		(pin "80"
		)
		(pin "8"
		)
		(pin "234"
		)
		(pin "236"
		)
		(pin "238"
		)
		(pin "89"
		)
		(pin "91"
		)
		(pin "93"
		)
		(pin "95"
		)
		(pin "97"
		)
		(pin "222"
		)
		(pin "224"
		)
		(pin "44"
		)
		(pin "135"
		)
		(pin "206"
		)
		(pin "211"
		)
		(pin "86"
		)
		(pin "108"
		)
		(pin "34"
		)
		(pin "218"
		)
		(pin "228"
		)
		(pin "47"
		)
		(pin "51"
		)
		(pin "262"
		)
		(pin "11"
		)
		(pin "203"
		)
		(pin "41"
		)
		(pin "45"
		)
		(pin "123"
		)
		(pin "161"
		)
		(pin "173"
		)
		(pin "174"
		)
		(pin "23"
		)
		(pin "24"
		)
		(pin "55"
		)
		(pin "28"
		)
		(pin "191"
		)
		(pin "27"
		)
		(pin "46"
		)
		(pin "48"
		)
		(pin "163"
		)
		(pin "166"
		)
		(pin "193"
		)
		(pin "195"
		)
		(pin "235"
		)
		(pin "110"
		)
		(pin "237"
		)
		(pin "58"
		)
		(pin "60"
		)
		(pin "175"
		)
		(pin "179"
		)
		(pin "162"
		)
		(pin "167"
		)
		(pin "145"
		)
		(pin "249"
		)
		(pin "157"
		)
		(pin "160"
		)
		(pin "189"
		)
		(pin "239"
		)
		(pin "38"
		)
		(pin "112"
		)
		(pin "5"
		)
		(pin "106"
		)
		(pin "244"
		)
		(pin "149"
		)
		(pin "150"
		)
		(pin "76"
		)
		(pin "94"
		)
		(pin "96"
		)
		(pin "196"
		)
		(pin "198"
		)
		(pin "98"
		)
		(pin "131"
		)
		(pin "116"
		)
		(pin "138"
		)
		(pin "32"
		)
		(pin "200"
		)
		(pin "56"
		)
		(instances
			(project "jetson-orin-baseboard"
				(path ""
					(reference "J15")
					(unit 5)
				)
			)
		)
	)
	(symbol
		(lib_id "antmicroCapacitorspol:C_Pol_100u_25V_KEMET-T521-D-107")
		(at 46.99 110.49 270)
		(unit 1)
		(exclude_from_sim no)
		(in_bom yes)
		(on_board yes)
		(dnp no)
		(property "Reference" "C2"
			(at 49.53 111.2266 90)
			(effects
				(font
					(size 1.27 1.27)
					(thickness 0.15)
				)
				(justify left)
			)
		)
		(property "Value" "C_Pol_100u_25V_KEMET-T521-D-107"
			(at 44.45 124.46 0)
			(effects
				(font
					(size 1.27 1.27)
					(thickness 0.15)
				)
				(justify left bottom)
				(hide yes)
			)
		)
		(property "Footprint" "antmicro-footprints:C_Pol_EIA-X"
			(at 39.37 124.46 0)
			(effects
				(font
					(size 1.27 1.27)
					(thickness 0.15)
				)
				(justify left bottom)
				(hide yes)
			)
		)
		(property "Datasheet" "https://content.kemet.com/datasheets/KEM_T2076_T52X-530.pdf"
			(at 36.83 124.46 0)
			(effects
				(font
					(size 1.27 1.27)
					(thickness 0.15)
				)
				(justify left bottom)
				(hide yes)
			)
		)
		(property "Description" "Surface Mount Tantalum Capacitor, 100 µF, 25 V, 2917 [7343 Metric], ± 20%, 0.04 ohm"
			(at 46.99 110.49 0)
			(effects
				(font
					(size 1.27 1.27)
				)
				(hide yes)
			)
		)
		(property "Val" "100u"
			(at 47.752 115.062 90)
			(effects
				(font
					(size 1.27 1.27)
					(thickness 0.15)
				)
				(justify left)
			)
		)
		(property "MPN" "T521D107M025ATE040"
			(at 34.29 124.46 0)
			(effects
				(font
					(size 1.27 1.27)
					(thickness 0.15)
				)
				(justify left bottom)
				(hide yes)
			)
		)
		(property "Manufacturer" "KEMET"
			(at 31.75 124.46 0)
			(effects
				(font
					(size 1.27 1.27)
					(thickness 0.15)
				)
				(justify left bottom)
				(hide yes)
			)
		)
		(property "License" "Apache-2.0"
			(at 29.21 124.46 0)
			(effects
				(font
					(size 1.27 1.27)
					(thickness 0.15)
				)
				(justify left bottom)
				(hide yes)
			)
		)
		(property "Author" "Antmicro"
			(at 26.67 124.46 0)
			(effects
				(font
					(size 1.27 1.27)
					(thickness 0.15)
				)
				(justify left bottom)
				(hide yes)
			)
		)
		(property "Voltage" "25V"
			(at 24.13 124.46 0)
			(effects
				(font
					(size 1.27 1.27)
				)
				(justify left bottom)
				(hide yes)
			)
		)
		(property "Dielectric" "template_dielectric"
			(at 21.59 124.46 0)
			(effects
				(font
					(size 1.27 1.27)
				)
				(justify left bottom)
				(hide yes)
			)
		)
		(pin "1"
		)
		(pin "2"
		)
		(instances
			(project "jetson-orin-baseboard"
				(path ""
					(reference "C2")
					(unit 1)
				)
			)
		)
	)
	(symbol
		(lib_name "GND_2")
		(lib_id "antmicropower:GND")
		(at 105.41 177.8 0)
		(unit 1)
		(exclude_from_sim no)
		(in_bom yes)
		(on_board yes)
		(dnp no)
		(property "Reference" "#PWR0112"
			(at 105.41 184.15 0)
			(effects
				(font
					(size 1.27 1.27)
				)
				(justify left bottom)
				(hide yes)
			)
		)
		(property "Value" "GND"
			(at 105.41 181.61 0)
			(effects
				(font
					(size 1.27 1.27)
					(thickness 0.15)
				)
			)
		)
		(property "Footprint" ""
			(at 114.3 185.42 0)
			(effects
				(font
					(size 1.27 1.27)
					(thickness 0.15)
				)
				(justify left bottom)
				(hide yes)
			)
		)
		(property "Datasheet" ""
			(at 114.3 190.5 0)
			(effects
				(font
					(size 1.27 1.27)
					(thickness 0.15)
				)
				(justify left bottom)
				(hide yes)
			)
		)
		(property "Description" ""
			(at 105.41 177.8 0)
			(effects
				(font
					(size 1.27 1.27)
				)
				(hide yes)
			)
		)
		(property "Author" "Antmicro"
			(at 114.3 185.42 0)
			(effects
				(font
					(size 1.27 1.27)
					(thickness 0.15)
				)
				(justify left bottom)
				(hide yes)
			)
		)
		(property "License" "Apache-2.0"
			(at 114.3 187.96 0)
			(effects
				(font
					(size 1.27 1.27)
					(thickness 0.15)
				)
				(justify left bottom)
				(hide yes)
			)
		)
		(pin "1"
		)
		(instances
			(project "jetson-orin-baseboard"
				(path ""
					(reference "#PWR0112")
					(unit 1)
				)
			)
		)
	)
	(symbol
		(lib_name "TP_0.75mm_SMD_5")
		(lib_id "antmicroTestPoints:TP_0.75mm_SMD")
		(at 293.37 109.22 0)
		(unit 1)
		(exclude_from_sim no)
		(in_bom no)
		(on_board yes)
		(dnp no)
		(property "Reference" "TP4"
			(at 297.18 109.22 0)
			(effects
				(font
					(size 1.27 1.27)
				)
				(justify left)
			)
		)
		(property "Value" "TP_0.75mm_SMD"
			(at 303.53 113.03 0)
			(effects
				(font
					(size 1.27 1.27)
					(thickness 0.15)
				)
				(justify left bottom)
				(hide yes)
			)
		)
		(property "Footprint" "antmicro-footprints:TP_SMD_0.75mm"
			(at 303.53 115.57 0)
			(effects
				(font
					(size 1.27 1.27)
					(thickness 0.15)
				)
				(justify left bottom)
				(hide yes)
			)
		)
		(property "Datasheet" ""
			(at 311.15 121.92 0)
			(effects
				(font
					(size 1.27 1.27)
					(thickness 0.15)
				)
				(justify left bottom)
				(hide yes)
			)
		)
		(property "Description" ""
			(at 293.37 109.22 0)
			(effects
				(font
					(size 1.27 1.27)
				)
				(hide yes)
			)
		)
		(property "MPN" ""
			(at 304.165 120.65 0)
			(effects
				(font
					(size 1.27 1.27)
					(thickness 0.15)
				)
				(justify left bottom)
				(hide yes)
			)
		)
		(property "Manufacturer" ""
			(at 304.165 115.57 0)
			(effects
				(font
					(size 1.27 1.27)
					(thickness 0.15)
				)
				(justify left bottom)
				(hide yes)
			)
		)
		(property "Author" "Antmicro"
			(at 303.53 118.11 0)
			(effects
				(font
					(size 1.27 1.27)
					(thickness 0.15)
				)
				(justify left bottom)
				(hide yes)
			)
		)
		(property "License" "Apache-2.0"
			(at 303.53 120.65 0)
			(effects
				(font
					(size 1.27 1.27)
					(thickness 0.15)
				)
				(justify left bottom)
				(hide yes)
			)
		)
		(pin "1"
		)
		(instances
			(project "jetson-orin-baseboard"
				(path ""
					(reference "TP4")
					(unit 1)
				)
			)
		)
	)
	(symbol
		(lib_id "antmicroPushbuttonSwitches:SW_KMR211NGLFS_SMD")
		(at 113.03 165.1 270)
		(unit 1)
		(exclude_from_sim no)
		(in_bom yes)
		(on_board yes)
		(dnp no)
		(fields_autoplaced yes)
		(property "Reference" "S1"
			(at 116.84 168.91 90)
			(effects
				(font
					(size 1.27 1.27)
				)
				(justify left)
			)
		)
		(property "Value" "SW_KMR211NGLFS_SMD"
			(at 105.41 190.5 0)
			(effects
				(font
					(size 1.27 1.27)
					(thickness 0.15)
				)
				(justify left bottom)
				(hide yes)
			)
		)
		(property "Footprint" "antmicro-footprints:SW_KMR211NGLFS_SMD"
			(at 102.87 190.5 0)
			(effects
				(font
					(size 1.27 1.27)
					(thickness 0.15)
				)
				(justify left bottom)
				(hide yes)
			)
		)
		(property "Datasheet" "http://www.farnell.com/datasheets/2631211.pdf"
			(at 100.33 190.5 0)
			(effects
				(font
					(size 1.27 1.27)
					(thickness 0.15)
				)
				(justify left bottom)
				(hide yes)
			)
		)
		(property "Description" ""
			(at 113.03 165.1 0)
			(effects
				(font
					(size 1.27 1.27)
				)
				(hide yes)
			)
		)
		(property "MPN" "KMR211NGLFS"
			(at 116.84 171.45 90)
			(effects
				(font
					(size 1.27 1.27)
					(thickness 0.15)
				)
				(justify left)
			)
		)
		(property "Manufacturer" "C&K"
			(at 97.79 190.5 0)
			(effects
				(font
					(size 1.27 1.27)
					(thickness 0.15)
				)
				(justify left bottom)
				(hide yes)
			)
		)
		(property "Author" "Antmicro"
			(at 95.25 190.5 0)
			(effects
				(font
					(size 1.27 1.27)
					(thickness 0.15)
				)
				(justify left bottom)
				(hide yes)
			)
		)
		(property "License" "Apache-2.0"
			(at 92.71 190.5 0)
			(effects
				(font
					(size 1.27 1.27)
					(thickness 0.15)
				)
				(justify left bottom)
				(hide yes)
			)
		)
		(pin "1"
		)
		(pin "2"
		)
		(pin "3"
		)
		(pin "4"
		)
		(instances
			(project "jetson-orin-baseboard"
				(path ""
					(reference "S1")
					(unit 1)
				)
			)
		)
	)
	(symbol
		(lib_id "antmicroModules:Jetson-Orin-NX-Nano")
		(at 201.93 266.7 0)
		(unit 1)
		(exclude_from_sim no)
		(in_bom no)
		(on_board yes)
		(dnp yes)
		(fields_autoplaced yes)
		(property "Reference" "M1"
			(at 207.01 259.08 0)
			(effects
				(font
					(size 1.27 1.27)
				)
			)
		)
		(property "Value" "Jetson-Orin-NX-Nano"
			(at 227.33 274.32 0)
			(effects
				(font
					(size 1.27 1.27)
					(thickness 0.15)
				)
				(justify left bottom)
				(hide yes)
			)
		)
		(property "Footprint" "antmicro-footprints:Module_Jetson-Orin-NX-Nano"
			(at 227.33 276.86 0)
			(effects
				(font
					(size 1.27 1.27)
					(thickness 0.15)
				)
				(justify left bottom)
				(hide yes)
			)
		)
		(property "Datasheet" "https://static6.arrow.com/aropdfconversion/c4902ff7fe8bae4b5d563d5e41c1cfab77501490/jetson-orin-nx-datasheet-nvidia-us-web-2605318-5.pdf"
			(at 227.33 279.4 0)
			(effects
				(font
					(size 1.27 1.27)
					(thickness 0.15)
				)
				(justify left bottom)
				(hide yes)
			)
		)
		(property "Description" ""
			(at 201.93 266.7 0)
			(effects
				(font
					(size 1.27 1.27)
				)
				(hide yes)
			)
		)
		(property "Manufacturer" "Nvidia"
			(at 227.33 281.94 0)
			(effects
				(font
					(size 1.27 1.27)
					(thickness 0.15)
				)
				(justify left bottom)
				(hide yes)
			)
		)
		(property "MPN" "900-13767-0000-000"
			(at 207.01 261.62 0)
			(effects
				(font
					(size 1.27 1.27)
					(thickness 0.15)
				)
			)
		)
		(property "Author" "Antmicro"
			(at 227.33 287.02 0)
			(effects
				(font
					(size 1.27 1.27)
					(thickness 0.15)
				)
				(justify left bottom)
				(hide yes)
			)
		)
		(property "License" "Apache-2.0"
			(at 227.33 289.56 0)
			(effects
				(font
					(size 1.27 1.27)
					(thickness 0.15)
				)
				(justify left bottom)
				(hide yes)
			)
		)
		(property "Displayed name" "Jetson Orin NX Nano"
			(at 227.33 292.1 0)
			(effects
				(font
					(size 1.27 1.27)
				)
				(justify left bottom)
			)
		)
		(instances
			(project "jetson-orin-baseboard"
				(path ""
					(reference "M1")
					(unit 1)
				)
			)
		)
	)
	(symbol
		(lib_id "antmicroBatteryHoldersClipsContacts:Battery_Holder_MS621FE-FL11E")
		(at 41.91 153.67 0)
		(unit 1)
		(exclude_from_sim no)
		(in_bom yes)
		(on_board yes)
		(dnp no)
		(fields_autoplaced yes)
		(property "Reference" "BT1"
			(at 38.1 156.845 0)
			(effects
				(font
					(size 1.27 1.27)
					(thickness 0.15)
				)
				(justify right)
			)
		)
		(property "Value" "Battery_Holder_MS621FE-FL11E"
			(at 59.69 161.29 0)
			(effects
				(font
					(size 1.27 1.27)
					(thickness 0.15)
				)
				(justify left bottom)
				(hide yes)
			)
		)
		(property "Footprint" "antmicro-footprints:MS621FE-FL11E"
			(at 59.69 163.83 0)
			(effects
				(font
					(size 1.27 1.27)
					(thickness 0.15)
				)
				(justify left bottom)
				(hide yes)
			)
		)
		(property "Datasheet" "https://www.sii.co.jp/en/me/datasheets/ms-rechargeable/ms621fe/"
			(at 59.69 166.37 0)
			(effects
				(font
					(size 1.27 1.27)
					(thickness 0.15)
				)
				(justify left bottom)
				(hide yes)
			)
		)
		(property "Description" ""
			(at 41.91 153.67 0)
			(effects
				(font
					(size 1.27 1.27)
				)
				(hide yes)
			)
		)
		(property "Manufacturer" "Seiko Instruments"
			(at 59.69 168.91 0)
			(effects
				(font
					(size 1.27 1.27)
					(thickness 0.15)
				)
				(justify left bottom)
				(hide yes)
			)
		)
		(property "MPN" "MS621FE-FL11E"
			(at 38.1 159.385 0)
			(effects
				(font
					(size 1.27 1.27)
					(thickness 0.15)
				)
				(justify right)
			)
		)
		(property "Author" "Antmicro"
			(at 59.69 171.45 0)
			(effects
				(font
					(size 1.27 1.27)
					(thickness 0.15)
				)
				(justify left bottom)
				(hide yes)
			)
		)
		(property "License" "Apache-2.0"
			(at 59.69 173.99 0)
			(effects
				(font
					(size 1.27 1.27)
					(thickness 0.15)
				)
				(justify left bottom)
				(hide yes)
			)
		)
		(pin "2"
		)
		(pin "1"
		)
		(instances
			(project "jetson-orin-baseboard"
				(path ""
					(reference "BT1")
					(unit 1)
				)
			)
		)
	)
	(symbol
		(lib_id "antmicroSoMConnectors:Bus_DDR4_SODIMM_CUSTOM_Jetson-Orin-H9.2mm-socket")
		(at 276.86 38.1 0)
		(mirror y)
		(unit 2)
		(exclude_from_sim no)
		(in_bom yes)
		(on_board yes)
		(dnp no)
		(fields_autoplaced yes)
		(property "Reference" "J15"
			(at 257.175 30.48 0)
			(effects
				(font
					(size 1.27 1.27)
					(thickness 0.15)
				)
			)
		)
		(property "Value" "Bus_DDR4_SODIMM_CUSTOM_Jetson-Orin-H9.2mm-socket"
			(at 214.63 45.72 0)
			(effects
				(font
					(size 1.27 1.27)
					(thickness 0.15)
				)
				(justify left bottom)
				(hide yes)
			)
		)
		(property "Footprint" "antmicro-footprints:TE_2309413"
			(at 214.63 48.26 0)
			(effects
				(font
					(size 1.27 1.27)
					(thickness 0.15)
				)
				(justify left bottom)
				(hide yes)
			)
		)
		(property "Datasheet" "https://developer.nvidia.com/jetson-orin-nx-series-data-sheet"
			(at 214.63 50.8 0)
			(effects
				(font
					(size 1.27 1.27)
					(thickness 0.15)
				)
				(justify left bottom)
				(hide yes)
			)
		)
		(property "Description" ""
			(at 276.86 38.1 0)
			(effects
				(font
					(size 1.27 1.27)
				)
				(hide yes)
			)
		)
		(property "Manufacturer" "TE Connectivity"
			(at 214.63 53.34 0)
			(effects
				(font
					(size 1.27 1.27)
					(thickness 0.15)
				)
				(justify left bottom)
				(hide yes)
			)
		)
		(property "MPN" "2309413-1"
			(at 257.175 33.02 0)
			(effects
				(font
					(size 1.27 1.27)
					(thickness 0.15)
				)
			)
		)
		(property "License" "Apache-2.0"
			(at 214.63 58.42 0)
			(effects
				(font
					(size 1.27 1.27)
					(thickness 0.15)
				)
				(justify left bottom)
				(hide yes)
			)
		)
		(property "Author" "Antmicro"
			(at 214.63 60.96 0)
			(effects
				(font
					(size 1.27 1.27)
					(thickness 0.15)
				)
				(justify left bottom)
				(hide yes)
			)
		)
		(pin "245"
		)
		(pin "227"
		)
		(pin "229"
		)
		(pin "158"
		)
		(pin "184"
		)
		(pin "186"
		)
		(pin "248"
		)
		(pin "25"
		)
		(pin "16"
		)
		(pin "250"
		)
		(pin "35"
		)
		(pin "142"
		)
		(pin "148"
		)
		(pin "133"
		)
		(pin "134"
		)
		(pin "77"
		)
		(pin "81"
		)
		(pin "136"
		)
		(pin "137"
		)
		(pin "207"
		)
		(pin "168"
		)
		(pin "39"
		)
		(pin "36"
		)
		(pin "65"
		)
		(pin "69"
		)
		(pin "21"
		)
		(pin "209"
		)
		(pin "139"
		)
		(pin "140"
		)
		(pin "205"
		)
		(pin "182"
		)
		(pin "183"
		)
		(pin "107"
		)
		(pin "72"
		)
		(pin "84"
		)
		(pin "212"
		)
		(pin "216"
		)
		(pin "114"
		)
		(pin "50"
		)
		(pin "199"
		)
		(pin "68"
		)
		(pin "37"
		)
		(pin "31"
		)
		(pin "74"
		)
		(pin "252"
		)
		(pin "7"
		)
		(pin "197"
		)
		(pin "53"
		)
		(pin "57"
		)
		(pin "202"
		)
		(pin "204"
		)
		(pin "261"
		)
		(pin "100"
		)
		(pin "63"
		)
		(pin "15"
		)
		(pin "17"
		)
		(pin "6"
		)
		(pin "201"
		)
		(pin "169"
		)
		(pin "172"
		)
		(pin "4"
		)
		(pin "2"
		)
		(pin "159"
		)
		(pin "43"
		)
		(pin "70"
		)
		(pin "141"
		)
		(pin "3"
		)
		(pin "29"
		)
		(pin "233"
		)
		(pin "164"
		)
		(pin "147"
		)
		(pin "10"
		)
		(pin "219"
		)
		(pin "221"
		)
		(pin "40"
		)
		(pin "42"
		)
		(pin "223"
		)
		(pin "225"
		)
		(pin "120"
		)
		(pin "122"
		)
		(pin "73"
		)
		(pin "117"
		)
		(pin "121"
		)
		(pin "12"
		)
		(pin "83"
		)
		(pin "88"
		)
		(pin "99"
		)
		(pin "109"
		)
		(pin "64"
		)
		(pin "66"
		)
		(pin "188"
		)
		(pin "190"
		)
		(pin "192"
		)
		(pin "194"
		)
		(pin "59"
		)
		(pin "87"
		)
		(pin "251"
		)
		(pin "90"
		)
		(pin "92"
		)
		(pin "71"
		)
		(pin "75"
		)
		(pin "119"
		)
		(pin "126"
		)
		(pin "127"
		)
		(pin "1"
		)
		(pin "102"
		)
		(pin "52"
		)
		(pin "54"
		)
		(pin "19"
		)
		(pin "253"
		)
		(pin "260"
		)
		(pin "230"
		)
		(pin "151"
		)
		(pin "154"
		)
		(pin "247"
		)
		(pin "67"
		)
		(pin "243"
		)
		(pin "155"
		)
		(pin "156"
		)
		(pin "20"
		)
		(pin "208"
		)
		(pin "242"
		)
		(pin "231"
		)
		(pin "14"
		)
		(pin "241"
		)
		(pin "78"
		)
		(pin "132"
		)
		(pin "18"
		)
		(pin "240"
		)
		(pin "171"
		)
		(pin "170"
		)
		(pin "153"
		)
		(pin "49"
		)
		(pin "178"
		)
		(pin "226"
		)
		(pin "232"
		)
		(pin "176"
		)
		(pin "185"
		)
		(pin "9"
		)
		(pin "152"
		)
		(pin "101"
		)
		(pin "143"
		)
		(pin "165"
		)
		(pin "257"
		)
		(pin "103"
		)
		(pin "85"
		)
		(pin "259"
		)
		(pin "104"
		)
		(pin "146"
		)
		(pin "220"
		)
		(pin "246"
		)
		(pin "180"
		)
		(pin "181"
		)
		(pin "105"
		)
		(pin "210"
		)
		(pin "254"
		)
		(pin "256"
		)
		(pin "118"
		)
		(pin "124"
		)
		(pin "217"
		)
		(pin "214"
		)
		(pin "255"
		)
		(pin "30"
		)
		(pin "111"
		)
		(pin "115"
		)
		(pin "258"
		)
		(pin "213"
		)
		(pin "82"
		)
		(pin "129"
		)
		(pin "144"
		)
		(pin "128"
		)
		(pin "130"
		)
		(pin "61"
		)
		(pin "79"
		)
		(pin "26"
		)
		(pin "215"
		)
		(pin "33"
		)
		(pin "13"
		)
		(pin "22"
		)
		(pin "62"
		)
		(pin "113"
		)
		(pin "187"
		)
		(pin "177"
		)
		(pin "125"
		)
		(pin "80"
		)
		(pin "8"
		)
		(pin "234"
		)
		(pin "236"
		)
		(pin "238"
		)
		(pin "89"
		)
		(pin "91"
		)
		(pin "93"
		)
		(pin "95"
		)
		(pin "97"
		)
		(pin "222"
		)
		(pin "224"
		)
		(pin "44"
		)
		(pin "135"
		)
		(pin "206"
		)
		(pin "211"
		)
		(pin "86"
		)
		(pin "108"
		)
		(pin "34"
		)
		(pin "218"
		)
		(pin "228"
		)
		(pin "47"
		)
		(pin "51"
		)
		(pin "262"
		)
		(pin "11"
		)
		(pin "203"
		)
		(pin "41"
		)
		(pin "45"
		)
		(pin "123"
		)
		(pin "161"
		)
		(pin "173"
		)
		(pin "174"
		)
		(pin "23"
		)
		(pin "24"
		)
		(pin "55"
		)
		(pin "28"
		)
		(pin "191"
		)
		(pin "27"
		)
		(pin "46"
		)
		(pin "48"
		)
		(pin "163"
		)
		(pin "166"
		)
		(pin "193"
		)
		(pin "195"
		)
		(pin "235"
		)
		(pin "110"
		)
		(pin "237"
		)
		(pin "58"
		)
		(pin "60"
		)
		(pin "175"
		)
		(pin "179"
		)
		(pin "162"
		)
		(pin "167"
		)
		(pin "145"
		)
		(pin "249"
		)
		(pin "157"
		)
		(pin "160"
		)
		(pin "189"
		)
		(pin "239"
		)
		(pin "38"
		)
		(pin "112"
		)
		(pin "5"
		)
		(pin "106"
		)
		(pin "244"
		)
		(pin "149"
		)
		(pin "150"
		)
		(pin "76"
		)
		(pin "94"
		)
		(pin "96"
		)
		(pin "196"
		)
		(pin "198"
		)
		(pin "98"
		)
		(pin "131"
		)
		(pin "116"
		)
		(pin "138"
		)
		(pin "32"
		)
		(pin "200"
		)
		(pin "56"
		)
		(instances
			(project "jetson-orin-baseboard"
				(path ""
					(reference "J15")
					(unit 2)
				)
			)
		)
	)
	(symbol
		(lib_id "antmicroSoMConnectors:Bus_DDR4_SODIMM_CUSTOM_Jetson-Orin-H9.2mm-socket")
		(at 365.76 38.1 0)
		(mirror y)
		(unit 6)
		(exclude_from_sim no)
		(in_bom yes)
		(on_board yes)
		(dnp no)
		(fields_autoplaced yes)
		(property "Reference" "J15"
			(at 346.075 30.48 0)
			(effects
				(font
					(size 1.27 1.27)
					(thickness 0.15)
				)
			)
		)
		(property "Value" "Bus_DDR4_SODIMM_CUSTOM_Jetson-Orin-H9.2mm-socket"
			(at 303.53 45.72 0)
			(effects
				(font
					(size 1.27 1.27)
					(thickness 0.15)
				)
				(justify left bottom)
				(hide yes)
			)
		)
		(property "Footprint" "antmicro-footprints:TE_2309413"
			(at 303.53 48.26 0)
			(effects
				(font
					(size 1.27 1.27)
					(thickness 0.15)
				)
				(justify left bottom)
				(hide yes)
			)
		)
		(property "Datasheet" "https://developer.nvidia.com/jetson-orin-nx-series-data-sheet"
			(at 303.53 50.8 0)
			(effects
				(font
					(size 1.27 1.27)
					(thickness 0.15)
				)
				(justify left bottom)
				(hide yes)
			)
		)
		(property "Description" ""
			(at 365.76 38.1 0)
			(effects
				(font
					(size 1.27 1.27)
				)
				(hide yes)
			)
		)
		(property "Manufacturer" "TE Connectivity"
			(at 303.53 53.34 0)
			(effects
				(font
					(size 1.27 1.27)
					(thickness 0.15)
				)
				(justify left bottom)
				(hide yes)
			)
		)
		(property "MPN" "2309413-1"
			(at 346.075 33.02 0)
			(effects
				(font
					(size 1.27 1.27)
					(thickness 0.15)
				)
			)
		)
		(property "License" "Apache-2.0"
			(at 303.53 58.42 0)
			(effects
				(font
					(size 1.27 1.27)
					(thickness 0.15)
				)
				(justify left bottom)
				(hide yes)
			)
		)
		(property "Author" "Antmicro"
			(at 303.53 60.96 0)
			(effects
				(font
					(size 1.27 1.27)
					(thickness 0.15)
				)
				(justify left bottom)
				(hide yes)
			)
		)
		(pin "245"
		)
		(pin "227"
		)
		(pin "229"
		)
		(pin "158"
		)
		(pin "184"
		)
		(pin "186"
		)
		(pin "248"
		)
		(pin "25"
		)
		(pin "16"
		)
		(pin "250"
		)
		(pin "35"
		)
		(pin "142"
		)
		(pin "148"
		)
		(pin "133"
		)
		(pin "134"
		)
		(pin "77"
		)
		(pin "81"
		)
		(pin "136"
		)
		(pin "137"
		)
		(pin "207"
		)
		(pin "168"
		)
		(pin "39"
		)
		(pin "36"
		)
		(pin "65"
		)
		(pin "69"
		)
		(pin "21"
		)
		(pin "209"
		)
		(pin "139"
		)
		(pin "140"
		)
		(pin "205"
		)
		(pin "182"
		)
		(pin "183"
		)
		(pin "107"
		)
		(pin "72"
		)
		(pin "84"
		)
		(pin "212"
		)
		(pin "216"
		)
		(pin "114"
		)
		(pin "50"
		)
		(pin "199"
		)
		(pin "68"
		)
		(pin "37"
		)
		(pin "31"
		)
		(pin "74"
		)
		(pin "252"
		)
		(pin "7"
		)
		(pin "197"
		)
		(pin "53"
		)
		(pin "57"
		)
		(pin "202"
		)
		(pin "204"
		)
		(pin "261"
		)
		(pin "100"
		)
		(pin "63"
		)
		(pin "15"
		)
		(pin "17"
		)
		(pin "6"
		)
		(pin "201"
		)
		(pin "169"
		)
		(pin "172"
		)
		(pin "4"
		)
		(pin "2"
		)
		(pin "159"
		)
		(pin "43"
		)
		(pin "70"
		)
		(pin "141"
		)
		(pin "3"
		)
		(pin "29"
		)
		(pin "233"
		)
		(pin "164"
		)
		(pin "147"
		)
		(pin "10"
		)
		(pin "219"
		)
		(pin "221"
		)
		(pin "40"
		)
		(pin "42"
		)
		(pin "223"
		)
		(pin "225"
		)
		(pin "120"
		)
		(pin "122"
		)
		(pin "73"
		)
		(pin "117"
		)
		(pin "121"
		)
		(pin "12"
		)
		(pin "83"
		)
		(pin "88"
		)
		(pin "99"
		)
		(pin "109"
		)
		(pin "64"
		)
		(pin "66"
		)
		(pin "188"
		)
		(pin "190"
		)
		(pin "192"
		)
		(pin "194"
		)
		(pin "59"
		)
		(pin "87"
		)
		(pin "251"
		)
		(pin "90"
		)
		(pin "92"
		)
		(pin "71"
		)
		(pin "75"
		)
		(pin "119"
		)
		(pin "126"
		)
		(pin "127"
		)
		(pin "1"
		)
		(pin "102"
		)
		(pin "52"
		)
		(pin "54"
		)
		(pin "19"
		)
		(pin "253"
		)
		(pin "260"
		)
		(pin "230"
		)
		(pin "151"
		)
		(pin "154"
		)
		(pin "247"
		)
		(pin "67"
		)
		(pin "243"
		)
		(pin "155"
		)
		(pin "156"
		)
		(pin "20"
		)
		(pin "208"
		)
		(pin "242"
		)
		(pin "231"
		)
		(pin "14"
		)
		(pin "241"
		)
		(pin "78"
		)
		(pin "132"
		)
		(pin "18"
		)
		(pin "240"
		)
		(pin "171"
		)
		(pin "170"
		)
		(pin "153"
		)
		(pin "49"
		)
		(pin "178"
		)
		(pin "226"
		)
		(pin "232"
		)
		(pin "176"
		)
		(pin "185"
		)
		(pin "9"
		)
		(pin "152"
		)
		(pin "101"
		)
		(pin "143"
		)
		(pin "165"
		)
		(pin "257"
		)
		(pin "103"
		)
		(pin "85"
		)
		(pin "259"
		)
		(pin "104"
		)
		(pin "146"
		)
		(pin "220"
		)
		(pin "246"
		)
		(pin "180"
		)
		(pin "181"
		)
		(pin "105"
		)
		(pin "210"
		)
		(pin "254"
		)
		(pin "256"
		)
		(pin "118"
		)
		(pin "124"
		)
		(pin "217"
		)
		(pin "214"
		)
		(pin "255"
		)
		(pin "30"
		)
		(pin "111"
		)
		(pin "115"
		)
		(pin "258"
		)
		(pin "213"
		)
		(pin "82"
		)
		(pin "129"
		)
		(pin "144"
		)
		(pin "128"
		)
		(pin "130"
		)
		(pin "61"
		)
		(pin "79"
		)
		(pin "26"
		)
		(pin "215"
		)
		(pin "33"
		)
		(pin "13"
		)
		(pin "22"
		)
		(pin "62"
		)
		(pin "113"
		)
		(pin "187"
		)
		(pin "177"
		)
		(pin "125"
		)
		(pin "80"
		)
		(pin "8"
		)
		(pin "234"
		)
		(pin "236"
		)
		(pin "238"
		)
		(pin "89"
		)
		(pin "91"
		)
		(pin "93"
		)
		(pin "95"
		)
		(pin "97"
		)
		(pin "222"
		)
		(pin "224"
		)
		(pin "44"
		)
		(pin "135"
		)
		(pin "206"
		)
		(pin "211"
		)
		(pin "86"
		)
		(pin "108"
		)
		(pin "34"
		)
		(pin "218"
		)
		(pin "228"
		)
		(pin "47"
		)
		(pin "51"
		)
		(pin "262"
		)
		(pin "11"
		)
		(pin "203"
		)
		(pin "41"
		)
		(pin "45"
		)
		(pin "123"
		)
		(pin "161"
		)
		(pin "173"
		)
		(pin "174"
		)
		(pin "23"
		)
		(pin "24"
		)
		(pin "55"
		)
		(pin "28"
		)
		(pin "191"
		)
		(pin "27"
		)
		(pin "46"
		)
		(pin "48"
		)
		(pin "163"
		)
		(pin "166"
		)
		(pin "193"
		)
		(pin "195"
		)
		(pin "235"
		)
		(pin "110"
		)
		(pin "237"
		)
		(pin "58"
		)
		(pin "60"
		)
		(pin "175"
		)
		(pin "179"
		)
		(pin "162"
		)
		(pin "167"
		)
		(pin "145"
		)
		(pin "249"
		)
		(pin "157"
		)
		(pin "160"
		)
		(pin "189"
		)
		(pin "239"
		)
		(pin "38"
		)
		(pin "112"
		)
		(pin "5"
		)
		(pin "106"
		)
		(pin "244"
		)
		(pin "149"
		)
		(pin "150"
		)
		(pin "76"
		)
		(pin "94"
		)
		(pin "96"
		)
		(pin "196"
		)
		(pin "198"
		)
		(pin "98"
		)
		(pin "131"
		)
		(pin "116"
		)
		(pin "138"
		)
		(pin "32"
		)
		(pin "200"
		)
		(pin "56"
		)
		(instances
			(project "jetson-orin-baseboard"
				(path ""
					(reference "J15")
					(unit 6)
				)
			)
		)
	)
	(symbol
		(lib_id "antmicroCapacitors0402:C_100n_0402")
		(at 91.44 242.57 270)
		(mirror x)
		(unit 1)
		(exclude_from_sim no)
		(in_bom yes)
		(on_board yes)
		(dnp no)
		(fields_autoplaced yes)
		(property "Reference" "C41"
			(at 93.98 238.7536 90)
			(effects
				(font
					(size 1.27 1.27)
				)
				(justify left)
			)
		)
		(property "Value" "C_100n_0402"
			(at 81.28 222.25 0)
			(effects
				(font
					(size 1.27 1.27)
					(thickness 0.15)
				)
				(justify left bottom)
				(hide yes)
			)
		)
		(property "Footprint" "antmicro-footprints:C_0402_1005Metric"
			(at 78.74 222.25 0)
			(effects
				(font
					(size 1.27 1.27)
					(thickness 0.15)
				)
				(justify left bottom)
				(hide yes)
			)
		)
		(property "Datasheet" "https://www.murata.com/products/productdetail?partno=GRM155R61H104KE14%23"
			(at 76.2 222.25 0)
			(effects
				(font
					(size 1.27 1.27)
					(thickness 0.15)
				)
				(justify left bottom)
				(hide yes)
			)
		)
		(property "Description" ""
			(at 91.44 242.57 0)
			(effects
				(font
					(size 1.27 1.27)
				)
				(hide yes)
			)
		)
		(property "Manufacturer" "Murata"
			(at 71.12 222.25 0)
			(effects
				(font
					(size 1.27 1.27)
					(thickness 0.15)
				)
				(justify left bottom)
				(hide yes)
			)
		)
		(property "MPN" "GRM155R61H104KE14D"
			(at 73.66 222.25 0)
			(effects
				(font
					(size 1.27 1.27)
					(thickness 0.15)
				)
				(justify left bottom)
				(hide yes)
			)
		)
		(property "Val" "100n"
			(at 93.98 241.2936 90)
			(effects
				(font
					(size 1.27 1.27)
					(thickness 0.15)
				)
				(justify left)
			)
		)
		(property "License" "Apache-2.0"
			(at 68.58 222.25 0)
			(effects
				(font
					(size 1.27 1.27)
					(thickness 0.15)
				)
				(justify left bottom)
				(hide yes)
			)
		)
		(property "Author" "Antmicro"
			(at 66.04 222.25 0)
			(effects
				(font
					(size 1.27 1.27)
					(thickness 0.15)
				)
				(justify left bottom)
				(hide yes)
			)
		)
		(property "Voltage" "50V"
			(at 63.5 222.25 0)
			(effects
				(font
					(size 1.27 1.27)
				)
				(justify left bottom)
				(hide yes)
			)
		)
		(property "Dielectric" "X5R"
			(at 60.96 222.25 0)
			(effects
				(font
					(size 1.27 1.27)
				)
				(justify left bottom)
				(hide yes)
			)
		)
		(pin "1"
		)
		(pin "2"
		)
		(instances
			(project "jetson-orin-baseboard"
				(path ""
					(reference "C41")
					(unit 1)
				)
			)
		)
	)
	(symbol
		(lib_id "antmicroSoMConnectors:Bus_DDR4_SODIMM_CUSTOM_Jetson-Orin-H9.2mm-socket")
		(at 367.03 213.36 0)
		(mirror y)
		(unit 7)
		(exclude_from_sim no)
		(in_bom yes)
		(on_board yes)
		(dnp no)
		(fields_autoplaced yes)
		(property "Reference" "J15"
			(at 347.345 205.74 0)
			(effects
				(font
					(size 1.27 1.27)
					(thickness 0.15)
				)
			)
		)
		(property "Value" "Bus_DDR4_SODIMM_CUSTOM_Jetson-Orin-H9.2mm-socket"
			(at 304.8 220.98 0)
			(effects
				(font
					(size 1.27 1.27)
					(thickness 0.15)
				)
				(justify left bottom)
				(hide yes)
			)
		)
		(property "Footprint" "antmicro-footprints:TE_2309413"
			(at 304.8 223.52 0)
			(effects
				(font
					(size 1.27 1.27)
					(thickness 0.15)
				)
				(justify left bottom)
				(hide yes)
			)
		)
		(property "Datasheet" "https://developer.nvidia.com/jetson-orin-nx-series-data-sheet"
			(at 304.8 226.06 0)
			(effects
				(font
					(size 1.27 1.27)
					(thickness 0.15)
				)
				(justify left bottom)
				(hide yes)
			)
		)
		(property "Description" ""
			(at 367.03 213.36 0)
			(effects
				(font
					(size 1.27 1.27)
				)
				(hide yes)
			)
		)
		(property "Manufacturer" "TE Connectivity"
			(at 304.8 228.6 0)
			(effects
				(font
					(size 1.27 1.27)
					(thickness 0.15)
				)
				(justify left bottom)
				(hide yes)
			)
		)
		(property "MPN" "2309413-1"
			(at 347.345 208.28 0)
			(effects
				(font
					(size 1.27 1.27)
					(thickness 0.15)
				)
			)
		)
		(property "License" "Apache-2.0"
			(at 304.8 233.68 0)
			(effects
				(font
					(size 1.27 1.27)
					(thickness 0.15)
				)
				(justify left bottom)
				(hide yes)
			)
		)
		(property "Author" "Antmicro"
			(at 304.8 236.22 0)
			(effects
				(font
					(size 1.27 1.27)
					(thickness 0.15)
				)
				(justify left bottom)
				(hide yes)
			)
		)
		(pin "245"
		)
		(pin "227"
		)
		(pin "229"
		)
		(pin "158"
		)
		(pin "184"
		)
		(pin "186"
		)
		(pin "248"
		)
		(pin "25"
		)
		(pin "16"
		)
		(pin "250"
		)
		(pin "35"
		)
		(pin "142"
		)
		(pin "148"
		)
		(pin "133"
		)
		(pin "134"
		)
		(pin "77"
		)
		(pin "81"
		)
		(pin "136"
		)
		(pin "137"
		)
		(pin "207"
		)
		(pin "168"
		)
		(pin "39"
		)
		(pin "36"
		)
		(pin "65"
		)
		(pin "69"
		)
		(pin "21"
		)
		(pin "209"
		)
		(pin "139"
		)
		(pin "140"
		)
		(pin "205"
		)
		(pin "182"
		)
		(pin "183"
		)
		(pin "107"
		)
		(pin "72"
		)
		(pin "84"
		)
		(pin "212"
		)
		(pin "216"
		)
		(pin "114"
		)
		(pin "50"
		)
		(pin "199"
		)
		(pin "68"
		)
		(pin "37"
		)
		(pin "31"
		)
		(pin "74"
		)
		(pin "252"
		)
		(pin "7"
		)
		(pin "197"
		)
		(pin "53"
		)
		(pin "57"
		)
		(pin "202"
		)
		(pin "204"
		)
		(pin "261"
		)
		(pin "100"
		)
		(pin "63"
		)
		(pin "15"
		)
		(pin "17"
		)
		(pin "6"
		)
		(pin "201"
		)
		(pin "169"
		)
		(pin "172"
		)
		(pin "4"
		)
		(pin "2"
		)
		(pin "159"
		)
		(pin "43"
		)
		(pin "70"
		)
		(pin "141"
		)
		(pin "3"
		)
		(pin "29"
		)
		(pin "233"
		)
		(pin "164"
		)
		(pin "147"
		)
		(pin "10"
		)
		(pin "219"
		)
		(pin "221"
		)
		(pin "40"
		)
		(pin "42"
		)
		(pin "223"
		)
		(pin "225"
		)
		(pin "120"
		)
		(pin "122"
		)
		(pin "73"
		)
		(pin "117"
		)
		(pin "121"
		)
		(pin "12"
		)
		(pin "83"
		)
		(pin "88"
		)
		(pin "99"
		)
		(pin "109"
		)
		(pin "64"
		)
		(pin "66"
		)
		(pin "188"
		)
		(pin "190"
		)
		(pin "192"
		)
		(pin "194"
		)
		(pin "59"
		)
		(pin "87"
		)
		(pin "251"
		)
		(pin "90"
		)
		(pin "92"
		)
		(pin "71"
		)
		(pin "75"
		)
		(pin "119"
		)
		(pin "126"
		)
		(pin "127"
		)
		(pin "1"
		)
		(pin "102"
		)
		(pin "52"
		)
		(pin "54"
		)
		(pin "19"
		)
		(pin "253"
		)
		(pin "260"
		)
		(pin "230"
		)
		(pin "151"
		)
		(pin "154"
		)
		(pin "247"
		)
		(pin "67"
		)
		(pin "243"
		)
		(pin "155"
		)
		(pin "156"
		)
		(pin "20"
		)
		(pin "208"
		)
		(pin "242"
		)
		(pin "231"
		)
		(pin "14"
		)
		(pin "241"
		)
		(pin "78"
		)
		(pin "132"
		)
		(pin "18"
		)
		(pin "240"
		)
		(pin "171"
		)
		(pin "170"
		)
		(pin "153"
		)
		(pin "49"
		)
		(pin "178"
		)
		(pin "226"
		)
		(pin "232"
		)
		(pin "176"
		)
		(pin "185"
		)
		(pin "9"
		)
		(pin "152"
		)
		(pin "101"
		)
		(pin "143"
		)
		(pin "165"
		)
		(pin "257"
		)
		(pin "103"
		)
		(pin "85"
		)
		(pin "259"
		)
		(pin "104"
		)
		(pin "146"
		)
		(pin "220"
		)
		(pin "246"
		)
		(pin "180"
		)
		(pin "181"
		)
		(pin "105"
		)
		(pin "210"
		)
		(pin "254"
		)
		(pin "256"
		)
		(pin "118"
		)
		(pin "124"
		)
		(pin "217"
		)
		(pin "214"
		)
		(pin "255"
		)
		(pin "30"
		)
		(pin "111"
		)
		(pin "115"
		)
		(pin "258"
		)
		(pin "213"
		)
		(pin "82"
		)
		(pin "129"
		)
		(pin "144"
		)
		(pin "128"
		)
		(pin "130"
		)
		(pin "61"
		)
		(pin "79"
		)
		(pin "26"
		)
		(pin "215"
		)
		(pin "33"
		)
		(pin "13"
		)
		(pin "22"
		)
		(pin "62"
		)
		(pin "113"
		)
		(pin "187"
		)
		(pin "177"
		)
		(pin "125"
		)
		(pin "80"
		)
		(pin "8"
		)
		(pin "234"
		)
		(pin "236"
		)
		(pin "238"
		)
		(pin "89"
		)
		(pin "91"
		)
		(pin "93"
		)
		(pin "95"
		)
		(pin "97"
		)
		(pin "222"
		)
		(pin "224"
		)
		(pin "44"
		)
		(pin "135"
		)
		(pin "206"
		)
		(pin "211"
		)
		(pin "86"
		)
		(pin "108"
		)
		(pin "34"
		)
		(pin "218"
		)
		(pin "228"
		)
		(pin "47"
		)
		(pin "51"
		)
		(pin "262"
		)
		(pin "11"
		)
		(pin "203"
		)
		(pin "41"
		)
		(pin "45"
		)
		(pin "123"
		)
		(pin "161"
		)
		(pin "173"
		)
		(pin "174"
		)
		(pin "23"
		)
		(pin "24"
		)
		(pin "55"
		)
		(pin "28"
		)
		(pin "191"
		)
		(pin "27"
		)
		(pin "46"
		)
		(pin "48"
		)
		(pin "163"
		)
		(pin "166"
		)
		(pin "193"
		)
		(pin "195"
		)
		(pin "235"
		)
		(pin "110"
		)
		(pin "237"
		)
		(pin "58"
		)
		(pin "60"
		)
		(pin "175"
		)
		(pin "179"
		)
		(pin "162"
		)
		(pin "167"
		)
		(pin "145"
		)
		(pin "249"
		)
		(pin "157"
		)
		(pin "160"
		)
		(pin "189"
		)
		(pin "239"
		)
		(pin "38"
		)
		(pin "112"
		)
		(pin "5"
		)
		(pin "106"
		)
		(pin "244"
		)
		(pin "149"
		)
		(pin "150"
		)
		(pin "76"
		)
		(pin "94"
		)
		(pin "96"
		)
		(pin "196"
		)
		(pin "198"
		)
		(pin "98"
		)
		(pin "131"
		)
		(pin "116"
		)
		(pin "138"
		)
		(pin "32"
		)
		(pin "200"
		)
		(pin "56"
		)
		(instances
			(project "jetson-orin-baseboard"
				(path ""
					(reference "J15")
					(unit 7)
				)
			)
		)
	)
	(symbol
		(lib_name "TP_0.75mm_SMD_4")
		(lib_id "antmicroTestPoints:TP_0.75mm_SMD")
		(at 293.37 114.3 0)
		(unit 1)
		(exclude_from_sim no)
		(in_bom no)
		(on_board yes)
		(dnp no)
		(property "Reference" "TP5"
			(at 297.18 114.3 0)
			(effects
				(font
					(size 1.27 1.27)
				)
				(justify left)
			)
		)
		(property "Value" "TP_0.75mm_SMD"
			(at 303.53 118.11 0)
			(effects
				(font
					(size 1.27 1.27)
					(thickness 0.15)
				)
				(justify left bottom)
				(hide yes)
			)
		)
		(property "Footprint" "antmicro-footprints:TP_SMD_0.75mm"
			(at 303.53 120.65 0)
			(effects
				(font
					(size 1.27 1.27)
					(thickness 0.15)
				)
				(justify left bottom)
				(hide yes)
			)
		)
		(property "Datasheet" ""
			(at 311.15 127 0)
			(effects
				(font
					(size 1.27 1.27)
					(thickness 0.15)
				)
				(justify left bottom)
				(hide yes)
			)
		)
		(property "Description" ""
			(at 293.37 114.3 0)
			(effects
				(font
					(size 1.27 1.27)
				)
				(hide yes)
			)
		)
		(property "MPN" ""
			(at 304.165 125.73 0)
			(effects
				(font
					(size 1.27 1.27)
					(thickness 0.15)
				)
				(justify left bottom)
				(hide yes)
			)
		)
		(property "Manufacturer" ""
			(at 304.165 120.65 0)
			(effects
				(font
					(size 1.27 1.27)
					(thickness 0.15)
				)
				(justify left bottom)
				(hide yes)
			)
		)
		(property "Author" "Antmicro"
			(at 303.53 123.19 0)
			(effects
				(font
					(size 1.27 1.27)
					(thickness 0.15)
				)
				(justify left bottom)
				(hide yes)
			)
		)
		(property "License" "Apache-2.0"
			(at 303.53 125.73 0)
			(effects
				(font
					(size 1.27 1.27)
					(thickness 0.15)
				)
				(justify left bottom)
				(hide yes)
			)
		)
		(pin "1"
		)
		(instances
			(project "jetson-orin-baseboard"
				(path ""
					(reference "TP5")
					(unit 1)
				)
			)
		)
	)
	(symbol
		(lib_name "GND_6")
		(lib_id "antmicropower:GND")
		(at 91.44 243.84 0)
		(unit 1)
		(exclude_from_sim no)
		(in_bom yes)
		(on_board yes)
		(dnp no)
		(property "Reference" "#PWR0150"
			(at 91.44 250.19 0)
			(effects
				(font
					(size 1.27 1.27)
				)
				(justify left bottom)
				(hide yes)
			)
		)
		(property "Value" "GND"
			(at 91.44 247.65 0)
			(effects
				(font
					(size 1.27 1.27)
					(thickness 0.15)
				)
			)
		)
		(property "Footprint" ""
			(at 100.33 251.46 0)
			(effects
				(font
					(size 1.27 1.27)
					(thickness 0.15)
				)
				(justify left bottom)
				(hide yes)
			)
		)
		(property "Datasheet" ""
			(at 100.33 256.54 0)
			(effects
				(font
					(size 1.27 1.27)
					(thickness 0.15)
				)
				(justify left bottom)
				(hide yes)
			)
		)
		(property "Description" ""
			(at 91.44 243.84 0)
			(effects
				(font
					(size 1.27 1.27)
				)
				(hide yes)
			)
		)
		(property "Author" "Antmicro"
			(at 100.33 251.46 0)
			(effects
				(font
					(size 1.27 1.27)
					(thickness 0.15)
				)
				(justify left bottom)
				(hide yes)
			)
		)
		(property "License" "Apache-2.0"
			(at 100.33 254 0)
			(effects
				(font
					(size 1.27 1.27)
					(thickness 0.15)
				)
				(justify left bottom)
				(hide yes)
			)
		)
		(pin "1"
		)
		(instances
			(project "jetson-orin-baseboard"
				(path ""
					(reference "#PWR0150")
					(unit 1)
				)
			)
		)
	)
	(symbol
		(lib_id "antmicropower:+3V3")
		(at 91.44 234.95 0)
		(unit 1)
		(exclude_from_sim no)
		(in_bom yes)
		(on_board yes)
		(dnp no)
		(property "Reference" "#PWR0149"
			(at 91.44 238.76 0)
			(effects
				(font
					(size 1.27 1.27)
				)
				(justify left bottom)
				(hide yes)
			)
		)
		(property "Value" "+3V3"
			(at 88.265 231.775 0)
			(effects
				(font
					(size 1.27 1.27)
					(thickness 0.15)
				)
				(justify left bottom)
			)
		)
		(property "Footprint" ""
			(at 106.68 242.57 0)
			(effects
				(font
					(size 1.27 1.27)
					(thickness 0.15)
				)
				(justify left bottom)
				(hide yes)
			)
		)
		(property "Datasheet" ""
			(at 106.68 245.11 0)
			(effects
				(font
					(size 1.27 1.27)
					(thickness 0.15)
				)
				(justify left bottom)
				(hide yes)
			)
		)
		(property "Description" ""
			(at 91.44 234.95 0)
			(effects
				(font
					(size 1.27 1.27)
				)
				(hide yes)
			)
		)
		(property "Author" "Antmicro"
			(at 106.68 237.49 0)
			(effects
				(font
					(size 1.27 1.27)
					(thickness 0.15)
				)
				(justify left bottom)
				(hide yes)
			)
		)
		(property "License" "Apache-2.0"
			(at 106.68 240.03 0)
			(effects
				(font
					(size 1.27 1.27)
					(thickness 0.15)
				)
				(justify left bottom)
				(hide yes)
			)
		)
		(pin "1"
		)
		(instances
			(project "jetson-orin-baseboard"
				(path ""
					(reference "#PWR0149")
					(unit 1)
				)
			)
		)
	)
	(symbol
		(lib_id "antmicropower:+1V8")
		(at 60.96 234.95 0)
		(unit 1)
		(exclude_from_sim no)
		(in_bom yes)
		(on_board yes)
		(dnp no)
		(property "Reference" "#PWR0152"
			(at 60.96 238.76 0)
			(effects
				(font
					(size 1.27 1.27)
				)
				(justify left bottom)
				(hide yes)
			)
		)
		(property "Value" "+1V8"
			(at 57.785 231.775 0)
			(effects
				(font
					(size 1.27 1.27)
					(thickness 0.15)
				)
				(justify left bottom)
			)
		)
		(property "Footprint" ""
			(at 76.2 242.57 0)
			(effects
				(font
					(size 1.27 1.27)
					(thickness 0.15)
				)
				(justify left bottom)
				(hide yes)
			)
		)
		(property "Datasheet" ""
			(at 76.2 245.11 0)
			(effects
				(font
					(size 1.27 1.27)
					(thickness 0.15)
				)
				(justify left bottom)
				(hide yes)
			)
		)
		(property "Description" ""
			(at 60.96 234.95 0)
			(effects
				(font
					(size 1.27 1.27)
				)
				(hide yes)
			)
		)
		(property "Author" "Antmicro"
			(at 76.2 240.03 0)
			(effects
				(font
					(size 1.27 1.27)
					(thickness 0.15)
				)
				(justify left bottom)
				(hide yes)
			)
		)
		(property "License" "Apache-2.0"
			(at 76.2 242.57 0)
			(effects
				(font
					(size 1.27 1.27)
					(thickness 0.15)
				)
				(justify left bottom)
				(hide yes)
			)
		)
		(pin "1"
		)
		(instances
			(project "jetson-orin-baseboard"
				(path ""
					(reference "#PWR0152")
					(unit 1)
				)
			)
		)
	)
	(symbol
		(lib_name "R_0R_0402_4")
		(lib_id "antmicroResistors0402:R_0R_0402")
		(at 74.93 63.5 0)
		(unit 1)
		(exclude_from_sim no)
		(in_bom no)
		(on_board yes)
		(dnp yes)
		(property "Reference" "R5"
			(at 80.01 62.865 0)
			(effects
				(font
					(size 1.27 1.27)
				)
				(justify left bottom)
			)
		)
		(property "Value" "R_0R_0402"
			(at 95.25 76.2 0)
			(effects
				(font
					(size 1.27 1.27)
					(thickness 0.15)
				)
				(justify left bottom)
				(hide yes)
			)
		)
		(property "Footprint" "antmicro-footprints:R_0402_1005Metric"
			(at 95.25 78.74 0)
			(effects
				(font
					(size 1.27 1.27)
					(thickness 0.15)
				)
				(justify left bottom)
				(hide yes)
			)
		)
		(property "Datasheet" "https://industrial.panasonic.com/cdbs/www-data/pdf/RDA0000/AOA0000C301.pdf"
			(at 95.25 81.28 0)
			(effects
				(font
					(size 1.27 1.27)
					(thickness 0.15)
				)
				(justify left bottom)
				(hide yes)
			)
		)
		(property "Description" ""
			(at 74.93 63.5 0)
			(effects
				(font
					(size 1.27 1.27)
				)
				(hide yes)
			)
		)
		(property "Manufacturer" "Panasonic"
			(at 95.25 86.36 0)
			(effects
				(font
					(size 1.27 1.27)
					(thickness 0.15)
				)
				(justify left bottom)
				(hide yes)
			)
		)
		(property "MPN" "ERJ2GE0R00X"
			(at 95.25 83.82 0)
			(effects
				(font
					(size 1.27 1.27)
					(thickness 0.15)
				)
				(justify left bottom)
				(hide yes)
			)
		)
		(property "Val" "0R"
			(at 72.39 62.865 0)
			(effects
				(font
					(size 1.27 1.27)
					(thickness 0.15)
				)
				(justify left bottom)
			)
		)
		(property "License" "Apache-2.0"
			(at 95.25 88.9 0)
			(effects
				(font
					(size 1.27 1.27)
					(thickness 0.15)
				)
				(justify left bottom)
				(hide yes)
			)
		)
		(property "Author" "Antmicro"
			(at 95.25 91.44 0)
			(effects
				(font
					(size 1.27 1.27)
					(thickness 0.15)
				)
				(justify left bottom)
				(hide yes)
			)
		)
		(property "Tolerance" "~"
			(at 95.25 73.66 0)
			(effects
				(font
					(size 1.27 1.27)
				)
				(justify left bottom)
				(hide yes)
			)
		)
		(property "Current" "1A"
			(at 95.25 93.98 0)
			(effects
				(font
					(size 1.27 1.27)
					(thickness 0.15)
				)
				(justify left bottom)
				(hide yes)
			)
		)
		(pin "1"
		)
		(pin "2"
		)
		(instances
			(project "jetson-orin-baseboard"
				(path ""
					(reference "R5")
					(unit 1)
				)
			)
		)
	)
	(symbol
		(lib_id "antmicroDiodesRectifiersSingle:RB521S30T1G")
		(at 31.75 146.05 180)
		(unit 1)
		(exclude_from_sim no)
		(in_bom yes)
		(on_board yes)
		(dnp no)
		(property "Reference" "D34"
			(at 29.21 140.97 0)
			(effects
				(font
					(size 1.27 1.27)
				)
			)
		)
		(property "Value" "RB521S30T1G"
			(at 8.89 130.81 0)
			(effects
				(font
					(size 1.27 1.27)
					(thickness 0.15)
				)
				(justify left bottom)
				(hide yes)
			)
		)
		(property "Footprint" "antmicro-footprints:SOD-523"
			(at 8.89 135.89 0)
			(effects
				(font
					(size 1.27 1.27)
					(thickness 0.15)
				)
				(justify left bottom)
				(hide yes)
			)
		)
		(property "Datasheet" "https://www.onsemi.com/pdf/datasheet/rb521s30t1-d.pdf"
			(at 8.89 133.35 0)
			(effects
				(font
					(size 1.27 1.27)
					(thickness 0.15)
				)
				(justify left bottom)
				(hide yes)
			)
		)
		(property "Description" ""
			(at 31.75 146.05 0)
			(effects
				(font
					(size 1.27 1.27)
				)
				(hide yes)
			)
		)
		(property "MPN" "RB521S30T1G"
			(at 29.21 143.51 0)
			(effects
				(font
					(size 1.27 1.27)
					(thickness 0.15)
				)
			)
		)
		(property "Manufacturer" "ON Semiconductor"
			(at 8.89 128.27 0)
			(effects
				(font
					(size 1.27 1.27)
					(thickness 0.15)
				)
				(justify left bottom)
				(hide yes)
			)
		)
		(property "Author" "Antmicro"
			(at 8.89 125.73 0)
			(effects
				(font
					(size 1.27 1.27)
					(thickness 0.15)
				)
				(justify left bottom)
				(hide yes)
			)
		)
		(property "License" "Apache-2.0"
			(at 8.89 123.19 0)
			(effects
				(font
					(size 1.27 1.27)
					(thickness 0.15)
				)
				(justify left bottom)
				(hide yes)
			)
		)
		(pin "1"
		)
		(pin "2"
		)
		(instances
			(project "jetson-orin-baseboard"
				(path ""
					(reference "D34")
					(unit 1)
				)
			)
		)
	)
	(symbol
		(lib_id "antmicroCapacitors0402:C_100n_0402")
		(at 60.96 242.57 270)
		(mirror x)
		(unit 1)
		(exclude_from_sim no)
		(in_bom yes)
		(on_board yes)
		(dnp no)
		(fields_autoplaced yes)
		(property "Reference" "C40"
			(at 58.42 238.7536 90)
			(effects
				(font
					(size 1.27 1.27)
				)
				(justify right)
			)
		)
		(property "Value" "C_100n_0402"
			(at 50.8 222.25 0)
			(effects
				(font
					(size 1.27 1.27)
					(thickness 0.15)
				)
				(justify left bottom)
				(hide yes)
			)
		)
		(property "Footprint" "antmicro-footprints:C_0402_1005Metric"
			(at 48.26 222.25 0)
			(effects
				(font
					(size 1.27 1.27)
					(thickness 0.15)
				)
				(justify left bottom)
				(hide yes)
			)
		)
		(property "Datasheet" "https://www.murata.com/products/productdetail?partno=GRM155R61H104KE14%23"
			(at 45.72 222.25 0)
			(effects
				(font
					(size 1.27 1.27)
					(thickness 0.15)
				)
				(justify left bottom)
				(hide yes)
			)
		)
		(property "Description" ""
			(at 60.96 242.57 0)
			(effects
				(font
					(size 1.27 1.27)
				)
				(hide yes)
			)
		)
		(property "Manufacturer" "Murata"
			(at 40.64 222.25 0)
			(effects
				(font
					(size 1.27 1.27)
					(thickness 0.15)
				)
				(justify left bottom)
				(hide yes)
			)
		)
		(property "MPN" "GRM155R61H104KE14D"
			(at 43.18 222.25 0)
			(effects
				(font
					(size 1.27 1.27)
					(thickness 0.15)
				)
				(justify left bottom)
				(hide yes)
			)
		)
		(property "Val" "100n"
			(at 58.42 241.2936 90)
			(effects
				(font
					(size 1.27 1.27)
					(thickness 0.15)
				)
				(justify right)
			)
		)
		(property "License" "Apache-2.0"
			(at 38.1 222.25 0)
			(effects
				(font
					(size 1.27 1.27)
					(thickness 0.15)
				)
				(justify left bottom)
				(hide yes)
			)
		)
		(property "Author" "Antmicro"
			(at 35.56 222.25 0)
			(effects
				(font
					(size 1.27 1.27)
					(thickness 0.15)
				)
				(justify left bottom)
				(hide yes)
			)
		)
		(property "Voltage" "50V"
			(at 33.02 222.25 0)
			(effects
				(font
					(size 1.27 1.27)
				)
				(justify left bottom)
				(hide yes)
			)
		)
		(property "Dielectric" "X5R"
			(at 30.48 222.25 0)
			(effects
				(font
					(size 1.27 1.27)
				)
				(justify left bottom)
				(hide yes)
			)
		)
		(pin "1"
		)
		(pin "2"
		)
		(instances
			(project "jetson-orin-baseboard"
				(path ""
					(reference "C40")
					(unit 1)
				)
			)
		)
	)
	(symbol
		(lib_id "antmicropower:+5V")
		(at 24.13 106.68 0)
		(unit 1)
		(exclude_from_sim no)
		(in_bom yes)
		(on_board yes)
		(dnp no)
		(property "Reference" "#PWR07"
			(at 24.13 110.49 0)
			(effects
				(font
					(size 1.27 1.27)
				)
				(justify left bottom)
				(hide yes)
			)
		)
		(property "Value" "VDD_SoM"
			(at 24.13 102.87 0)
			(effects
				(font
					(size 1.27 1.27)
					(thickness 0.15)
				)
			)
		)
		(property "Footprint" ""
			(at 39.37 114.3 0)
			(effects
				(font
					(size 1.27 1.27)
					(thickness 0.15)
				)
				(justify left bottom)
				(hide yes)
			)
		)
		(property "Datasheet" ""
			(at 39.37 116.84 0)
			(effects
				(font
					(size 1.27 1.27)
					(thickness 0.15)
				)
				(justify left bottom)
				(hide yes)
			)
		)
		(property "Description" ""
			(at 24.13 106.68 0)
			(effects
				(font
					(size 1.27 1.27)
				)
				(hide yes)
			)
		)
		(property "Author" "Antmicro"
			(at 39.37 114.3 0)
			(effects
				(font
					(size 1.27 1.27)
					(thickness 0.15)
				)
				(justify left bottom)
				(hide yes)
			)
		)
		(property "License" "Apache-2.0"
			(at 39.37 116.84 0)
			(effects
				(font
					(size 1.27 1.27)
					(thickness 0.15)
				)
				(justify left bottom)
				(hide yes)
			)
		)
		(pin "1"
		)
		(instances
			(project "jetson-orin-baseboard"
				(path ""
					(reference "#PWR07")
					(unit 1)
				)
			)
		)
	)
	(symbol
		(lib_name "GND_3")
		(lib_id "antmicropower:GND")
		(at 46.99 116.84 0)
		(unit 1)
		(exclude_from_sim no)
		(in_bom yes)
		(on_board yes)
		(dnp no)
		(property "Reference" "#PWR02"
			(at 46.99 123.19 0)
			(effects
				(font
					(size 1.27 1.27)
				)
				(justify left bottom)
				(hide yes)
			)
		)
		(property "Value" "GND"
			(at 46.99 120.65 0)
			(effects
				(font
					(size 1.27 1.27)
					(thickness 0.15)
				)
				(hide yes)
			)
		)
		(property "Footprint" ""
			(at 55.88 124.46 0)
			(effects
				(font
					(size 1.27 1.27)
					(thickness 0.15)
				)
				(justify left bottom)
				(hide yes)
			)
		)
		(property "Datasheet" ""
			(at 55.88 129.54 0)
			(effects
				(font
					(size 1.27 1.27)
					(thickness 0.15)
				)
				(justify left bottom)
				(hide yes)
			)
		)
		(property "Description" ""
			(at 46.99 116.84 0)
			(effects
				(font
					(size 1.27 1.27)
				)
				(hide yes)
			)
		)
		(property "Author" "Antmicro"
			(at 55.88 124.46 0)
			(effects
				(font
					(size 1.27 1.27)
					(thickness 0.15)
				)
				(justify left bottom)
				(hide yes)
			)
		)
		(property "License" "Apache-2.0"
			(at 55.88 127 0)
			(effects
				(font
					(size 1.27 1.27)
					(thickness 0.15)
				)
				(justify left bottom)
				(hide yes)
			)
		)
		(pin "1"
		)
		(instances
			(project "jetson-orin-baseboard"
				(path ""
					(reference "#PWR02")
					(unit 1)
				)
			)
		)
	)
	(symbol
		(lib_id "antmicroMechanicalParts:Spacer_Drill3.7mm_H6.5mm_9774065151R")
		(at 152.4 266.7 0)
		(unit 1)
		(exclude_from_sim no)
		(in_bom yes)
		(on_board yes)
		(dnp no)
		(fields_autoplaced yes)
		(property "Reference" "H1"
			(at 161.29 265.43 0)
			(effects
				(font
					(size 1.27 1.27)
					(thickness 0.15)
				)
				(justify left)
			)
		)
		(property "Value" "Spacer_Drill3.7mm_H6.5mm_9774065151R"
			(at 167.64 276.86 0)
			(effects
				(font
					(size 1.27 1.27)
					(thickness 0.15)
				)
				(justify left bottom)
				(hide yes)
			)
		)
		(property "Footprint" "antmicro-footprints:Spacer_Drill3.7mm_H6.5mm_9774065151R"
			(at 167.64 279.4 0)
			(effects
				(font
					(size 1.27 1.27)
					(thickness 0.15)
				)
				(justify left bottom)
				(hide yes)
			)
		)
		(property "Datasheet" "https://www.we-online.com/components/products/datasheet/9774065151R.pdf"
			(at 167.64 281.94 0)
			(effects
				(font
					(size 1.27 1.27)
					(thickness 0.15)
				)
				(justify left bottom)
				(hide yes)
			)
		)
		(property "Description" ""
			(at 152.4 266.7 0)
			(effects
				(font
					(size 1.27 1.27)
				)
				(hide yes)
			)
		)
		(property "Manufacturer" "Würth Elektronik"
			(at 167.64 284.48 0)
			(effects
				(font
					(size 1.27 1.27)
					(thickness 0.15)
				)
				(justify left bottom)
				(hide yes)
			)
		)
		(property "MPN" "9774065151R"
			(at 161.29 267.97 0)
			(effects
				(font
					(size 1.27 1.27)
					(thickness 0.15)
				)
				(justify left)
			)
		)
		(property "Author" "Antmicro"
			(at 167.64 287.02 0)
			(effects
				(font
					(size 1.27 1.27)
					(thickness 0.15)
				)
				(justify left bottom)
				(hide yes)
			)
		)
		(property "License" "Apache-2.0"
			(at 167.64 289.56 0)
			(effects
				(font
					(size 1.27 1.27)
					(thickness 0.15)
				)
				(justify left bottom)
				(hide yes)
			)
		)
		(pin "1"
		)
		(instances
			(project "jetson-orin-baseboard"
				(path ""
					(reference "H1")
					(unit 1)
				)
			)
		)
	)
	(symbol
		(lib_name "GND_5")
		(lib_id "antmicropower:GND")
		(at 60.96 243.84 0)
		(unit 1)
		(exclude_from_sim no)
		(in_bom yes)
		(on_board yes)
		(dnp no)
		(property "Reference" "#PWR0153"
			(at 60.96 250.19 0)
			(effects
				(font
					(size 1.27 1.27)
				)
				(justify left bottom)
				(hide yes)
			)
		)
		(property "Value" "GND"
			(at 60.96 247.65 0)
			(effects
				(font
					(size 1.27 1.27)
					(thickness 0.15)
				)
			)
		)
		(property "Footprint" ""
			(at 69.85 251.46 0)
			(effects
				(font
					(size 1.27 1.27)
					(thickness 0.15)
				)
				(justify left bottom)
				(hide yes)
			)
		)
		(property "Datasheet" ""
			(at 69.85 256.54 0)
			(effects
				(font
					(size 1.27 1.27)
					(thickness 0.15)
				)
				(justify left bottom)
				(hide yes)
			)
		)
		(property "Description" ""
			(at 60.96 243.84 0)
			(effects
				(font
					(size 1.27 1.27)
				)
				(hide yes)
			)
		)
		(property "Author" "Antmicro"
			(at 69.85 251.46 0)
			(effects
				(font
					(size 1.27 1.27)
					(thickness 0.15)
				)
				(justify left bottom)
				(hide yes)
			)
		)
		(property "License" "Apache-2.0"
			(at 69.85 254 0)
			(effects
				(font
					(size 1.27 1.27)
					(thickness 0.15)
				)
				(justify left bottom)
				(hide yes)
			)
		)
		(pin "1"
		)
		(instances
			(project "jetson-orin-baseboard"
				(path ""
					(reference "#PWR0153")
					(unit 1)
				)
			)
		)
	)
	(symbol
		(lib_id "antmicroSoMConnectors:Bus_DDR4_SODIMM_CUSTOM_Jetson-Orin-H9.2mm-socket")
		(at 64.77 29.21 0)
		(mirror y)
		(unit 8)
		(exclude_from_sim no)
		(in_bom yes)
		(on_board yes)
		(dnp no)
		(fields_autoplaced yes)
		(property "Reference" "J15"
			(at 45.085 21.59 0)
			(effects
				(font
					(size 1.27 1.27)
					(thickness 0.15)
				)
			)
		)
		(property "Value" "Bus_DDR4_SODIMM_CUSTOM_Jetson-Orin-H9.2mm-socket"
			(at 2.54 36.83 0)
			(effects
				(font
					(size 1.27 1.27)
					(thickness 0.15)
				)
				(justify left bottom)
				(hide yes)
			)
		)
		(property "Footprint" "antmicro-footprints:TE_2309413"
			(at 2.54 39.37 0)
			(effects
				(font
					(size 1.27 1.27)
					(thickness 0.15)
				)
				(justify left bottom)
				(hide yes)
			)
		)
		(property "Datasheet" "https://developer.nvidia.com/jetson-orin-nx-series-data-sheet"
			(at 2.54 41.91 0)
			(effects
				(font
					(size 1.27 1.27)
					(thickness 0.15)
				)
				(justify left bottom)
				(hide yes)
			)
		)
		(property "Description" ""
			(at 64.77 29.21 0)
			(effects
				(font
					(size 1.27 1.27)
				)
				(hide yes)
			)
		)
		(property "Manufacturer" "TE Connectivity"
			(at 2.54 44.45 0)
			(effects
				(font
					(size 1.27 1.27)
					(thickness 0.15)
				)
				(justify left bottom)
				(hide yes)
			)
		)
		(property "MPN" "2309413-1"
			(at 45.085 24.13 0)
			(effects
				(font
					(size 1.27 1.27)
					(thickness 0.15)
				)
			)
		)
		(property "License" "Apache-2.0"
			(at 2.54 49.53 0)
			(effects
				(font
					(size 1.27 1.27)
					(thickness 0.15)
				)
				(justify left bottom)
				(hide yes)
			)
		)
		(property "Author" "Antmicro"
			(at 2.54 52.07 0)
			(effects
				(font
					(size 1.27 1.27)
					(thickness 0.15)
				)
				(justify left bottom)
				(hide yes)
			)
		)
		(pin "245"
		)
		(pin "227"
		)
		(pin "229"
		)
		(pin "158"
		)
		(pin "184"
		)
		(pin "186"
		)
		(pin "248"
		)
		(pin "25"
		)
		(pin "16"
		)
		(pin "250"
		)
		(pin "35"
		)
		(pin "142"
		)
		(pin "148"
		)
		(pin "133"
		)
		(pin "134"
		)
		(pin "77"
		)
		(pin "81"
		)
		(pin "136"
		)
		(pin "137"
		)
		(pin "207"
		)
		(pin "168"
		)
		(pin "39"
		)
		(pin "36"
		)
		(pin "65"
		)
		(pin "69"
		)
		(pin "21"
		)
		(pin "209"
		)
		(pin "139"
		)
		(pin "140"
		)
		(pin "205"
		)
		(pin "182"
		)
		(pin "183"
		)
		(pin "107"
		)
		(pin "72"
		)
		(pin "84"
		)
		(pin "212"
		)
		(pin "216"
		)
		(pin "114"
		)
		(pin "50"
		)
		(pin "199"
		)
		(pin "68"
		)
		(pin "37"
		)
		(pin "31"
		)
		(pin "74"
		)
		(pin "252"
		)
		(pin "7"
		)
		(pin "197"
		)
		(pin "53"
		)
		(pin "57"
		)
		(pin "202"
		)
		(pin "204"
		)
		(pin "261"
		)
		(pin "100"
		)
		(pin "63"
		)
		(pin "15"
		)
		(pin "17"
		)
		(pin "6"
		)
		(pin "201"
		)
		(pin "169"
		)
		(pin "172"
		)
		(pin "4"
		)
		(pin "2"
		)
		(pin "159"
		)
		(pin "43"
		)
		(pin "70"
		)
		(pin "141"
		)
		(pin "3"
		)
		(pin "29"
		)
		(pin "233"
		)
		(pin "164"
		)
		(pin "147"
		)
		(pin "10"
		)
		(pin "219"
		)
		(pin "221"
		)
		(pin "40"
		)
		(pin "42"
		)
		(pin "223"
		)
		(pin "225"
		)
		(pin "120"
		)
		(pin "122"
		)
		(pin "73"
		)
		(pin "117"
		)
		(pin "121"
		)
		(pin "12"
		)
		(pin "83"
		)
		(pin "88"
		)
		(pin "99"
		)
		(pin "109"
		)
		(pin "64"
		)
		(pin "66"
		)
		(pin "188"
		)
		(pin "190"
		)
		(pin "192"
		)
		(pin "194"
		)
		(pin "59"
		)
		(pin "87"
		)
		(pin "251"
		)
		(pin "90"
		)
		(pin "92"
		)
		(pin "71"
		)
		(pin "75"
		)
		(pin "119"
		)
		(pin "126"
		)
		(pin "127"
		)
		(pin "1"
		)
		(pin "102"
		)
		(pin "52"
		)
		(pin "54"
		)
		(pin "19"
		)
		(pin "253"
		)
		(pin "260"
		)
		(pin "230"
		)
		(pin "151"
		)
		(pin "154"
		)
		(pin "247"
		)
		(pin "67"
		)
		(pin "243"
		)
		(pin "155"
		)
		(pin "156"
		)
		(pin "20"
		)
		(pin "208"
		)
		(pin "242"
		)
		(pin "231"
		)
		(pin "14"
		)
		(pin "241"
		)
		(pin "78"
		)
		(pin "132"
		)
		(pin "18"
		)
		(pin "240"
		)
		(pin "171"
		)
		(pin "170"
		)
		(pin "153"
		)
		(pin "49"
		)
		(pin "178"
		)
		(pin "226"
		)
		(pin "232"
		)
		(pin "176"
		)
		(pin "185"
		)
		(pin "9"
		)
		(pin "152"
		)
		(pin "101"
		)
		(pin "143"
		)
		(pin "165"
		)
		(pin "257"
		)
		(pin "103"
		)
		(pin "85"
		)
		(pin "259"
		)
		(pin "104"
		)
		(pin "146"
		)
		(pin "220"
		)
		(pin "246"
		)
		(pin "180"
		)
		(pin "181"
		)
		(pin "105"
		)
		(pin "210"
		)
		(pin "254"
		)
		(pin "256"
		)
		(pin "118"
		)
		(pin "124"
		)
		(pin "217"
		)
		(pin "214"
		)
		(pin "255"
		)
		(pin "30"
		)
		(pin "111"
		)
		(pin "115"
		)
		(pin "258"
		)
		(pin "213"
		)
		(pin "82"
		)
		(pin "129"
		)
		(pin "144"
		)
		(pin "128"
		)
		(pin "130"
		)
		(pin "61"
		)
		(pin "79"
		)
		(pin "26"
		)
		(pin "215"
		)
		(pin "33"
		)
		(pin "13"
		)
		(pin "22"
		)
		(pin "62"
		)
		(pin "113"
		)
		(pin "187"
		)
		(pin "177"
		)
		(pin "125"
		)
		(pin "80"
		)
		(pin "8"
		)
		(pin "234"
		)
		(pin "236"
		)
		(pin "238"
		)
		(pin "89"
		)
		(pin "91"
		)
		(pin "93"
		)
		(pin "95"
		)
		(pin "97"
		)
		(pin "222"
		)
		(pin "224"
		)
		(pin "44"
		)
		(pin "135"
		)
		(pin "206"
		)
		(pin "211"
		)
		(pin "86"
		)
		(pin "108"
		)
		(pin "34"
		)
		(pin "218"
		)
		(pin "228"
		)
		(pin "47"
		)
		(pin "51"
		)
		(pin "262"
		)
		(pin "11"
		)
		(pin "203"
		)
		(pin "41"
		)
		(pin "45"
		)
		(pin "123"
		)
		(pin "161"
		)
		(pin "173"
		)
		(pin "174"
		)
		(pin "23"
		)
		(pin "24"
		)
		(pin "55"
		)
		(pin "28"
		)
		(pin "191"
		)
		(pin "27"
		)
		(pin "46"
		)
		(pin "48"
		)
		(pin "163"
		)
		(pin "166"
		)
		(pin "193"
		)
		(pin "195"
		)
		(pin "235"
		)
		(pin "110"
		)
		(pin "237"
		)
		(pin "58"
		)
		(pin "60"
		)
		(pin "175"
		)
		(pin "179"
		)
		(pin "162"
		)
		(pin "167"
		)
		(pin "145"
		)
		(pin "249"
		)
		(pin "157"
		)
		(pin "160"
		)
		(pin "189"
		)
		(pin "239"
		)
		(pin "38"
		)
		(pin "112"
		)
		(pin "5"
		)
		(pin "106"
		)
		(pin "244"
		)
		(pin "149"
		)
		(pin "150"
		)
		(pin "76"
		)
		(pin "94"
		)
		(pin "96"
		)
		(pin "196"
		)
		(pin "198"
		)
		(pin "98"
		)
		(pin "131"
		)
		(pin "116"
		)
		(pin "138"
		)
		(pin "32"
		)
		(pin "200"
		)
		(pin "56"
		)
		(instances
			(project "jetson-orin-baseboard"
				(path ""
					(reference "J15")
					(unit 8)
				)
			)
		)
	)
	(symbol
		(lib_id "antmicropower:GND")
		(at 151.13 276.86 0)
		(unit 1)
		(exclude_from_sim no)
		(in_bom yes)
		(on_board yes)
		(dnp no)
		(property "Reference" "#PWR018"
			(at 151.13 283.21 0)
			(effects
				(font
					(size 1.27 1.27)
				)
				(justify left bottom)
				(hide yes)
			)
		)
		(property "Value" "GND"
			(at 151.13 280.67 0)
			(effects
				(font
					(size 1.27 1.27)
					(thickness 0.15)
				)
			)
		)
		(property "Footprint" ""
			(at 160.02 284.48 0)
			(effects
				(font
					(size 1.27 1.27)
					(thickness 0.15)
				)
				(justify left bottom)
				(hide yes)
			)
		)
		(property "Datasheet" ""
			(at 160.02 289.56 0)
			(effects
				(font
					(size 1.27 1.27)
					(thickness 0.15)
				)
				(justify left bottom)
				(hide yes)
			)
		)
		(property "Description" ""
			(at 151.13 276.86 0)
			(effects
				(font
					(size 1.27 1.27)
				)
				(hide yes)
			)
		)
		(property "Author" "Antmicro"
			(at 160.02 284.48 0)
			(effects
				(font
					(size 1.27 1.27)
					(thickness 0.15)
				)
				(justify left bottom)
				(hide yes)
			)
		)
		(property "License" "Apache-2.0"
			(at 160.02 287.02 0)
			(effects
				(font
					(size 1.27 1.27)
					(thickness 0.15)
				)
				(justify left bottom)
				(hide yes)
			)
		)
		(pin "1"
		)
		(instances
			(project "jetson-orin-baseboard"
				(path ""
					(reference "#PWR018")
					(unit 1)
				)
			)
		)
	)
	(symbol
		(lib_id "antmicroSoMConnectors:Bus_DDR4_SODIMM_CUSTOM_Jetson-Orin-H9.2mm-socket")
		(at 189.23 186.69 0)
		(mirror y)
		(unit 4)
		(exclude_from_sim no)
		(in_bom yes)
		(on_board yes)
		(dnp no)
		(fields_autoplaced yes)
		(property "Reference" "J15"
			(at 169.545 179.07 0)
			(effects
				(font
					(size 1.27 1.27)
					(thickness 0.15)
				)
			)
		)
		(property "Value" "Bus_DDR4_SODIMM_CUSTOM_Jetson-Orin-H9.2mm-socket"
			(at 127 194.31 0)
			(effects
				(font
					(size 1.27 1.27)
					(thickness 0.15)
				)
				(justify left bottom)
				(hide yes)
			)
		)
		(property "Footprint" "antmicro-footprints:TE_2309413"
			(at 127 196.85 0)
			(effects
				(font
					(size 1.27 1.27)
					(thickness 0.15)
				)
				(justify left bottom)
				(hide yes)
			)
		)
		(property "Datasheet" "https://developer.nvidia.com/jetson-orin-nx-series-data-sheet"
			(at 127 199.39 0)
			(effects
				(font
					(size 1.27 1.27)
					(thickness 0.15)
				)
				(justify left bottom)
				(hide yes)
			)
		)
		(property "Description" ""
			(at 189.23 186.69 0)
			(effects
				(font
					(size 1.27 1.27)
				)
				(hide yes)
			)
		)
		(property "Manufacturer" "TE Connectivity"
			(at 127 201.93 0)
			(effects
				(font
					(size 1.27 1.27)
					(thickness 0.15)
				)
				(justify left bottom)
				(hide yes)
			)
		)
		(property "MPN" "2309413-1"
			(at 169.545 181.61 0)
			(effects
				(font
					(size 1.27 1.27)
					(thickness 0.15)
				)
			)
		)
		(property "License" "Apache-2.0"
			(at 127 207.01 0)
			(effects
				(font
					(size 1.27 1.27)
					(thickness 0.15)
				)
				(justify left bottom)
				(hide yes)
			)
		)
		(property "Author" "Antmicro"
			(at 127 209.55 0)
			(effects
				(font
					(size 1.27 1.27)
					(thickness 0.15)
				)
				(justify left bottom)
				(hide yes)
			)
		)
		(pin "245"
		)
		(pin "227"
		)
		(pin "229"
		)
		(pin "158"
		)
		(pin "184"
		)
		(pin "186"
		)
		(pin "248"
		)
		(pin "25"
		)
		(pin "16"
		)
		(pin "250"
		)
		(pin "35"
		)
		(pin "142"
		)
		(pin "148"
		)
		(pin "133"
		)
		(pin "134"
		)
		(pin "77"
		)
		(pin "81"
		)
		(pin "136"
		)
		(pin "137"
		)
		(pin "207"
		)
		(pin "168"
		)
		(pin "39"
		)
		(pin "36"
		)
		(pin "65"
		)
		(pin "69"
		)
		(pin "21"
		)
		(pin "209"
		)
		(pin "139"
		)
		(pin "140"
		)
		(pin "205"
		)
		(pin "182"
		)
		(pin "183"
		)
		(pin "107"
		)
		(pin "72"
		)
		(pin "84"
		)
		(pin "212"
		)
		(pin "216"
		)
		(pin "114"
		)
		(pin "50"
		)
		(pin "199"
		)
		(pin "68"
		)
		(pin "37"
		)
		(pin "31"
		)
		(pin "74"
		)
		(pin "252"
		)
		(pin "7"
		)
		(pin "197"
		)
		(pin "53"
		)
		(pin "57"
		)
		(pin "202"
		)
		(pin "204"
		)
		(pin "261"
		)
		(pin "100"
		)
		(pin "63"
		)
		(pin "15"
		)
		(pin "17"
		)
		(pin "6"
		)
		(pin "201"
		)
		(pin "169"
		)
		(pin "172"
		)
		(pin "4"
		)
		(pin "2"
		)
		(pin "159"
		)
		(pin "43"
		)
		(pin "70"
		)
		(pin "141"
		)
		(pin "3"
		)
		(pin "29"
		)
		(pin "233"
		)
		(pin "164"
		)
		(pin "147"
		)
		(pin "10"
		)
		(pin "219"
		)
		(pin "221"
		)
		(pin "40"
		)
		(pin "42"
		)
		(pin "223"
		)
		(pin "225"
		)
		(pin "120"
		)
		(pin "122"
		)
		(pin "73"
		)
		(pin "117"
		)
		(pin "121"
		)
		(pin "12"
		)
		(pin "83"
		)
		(pin "88"
		)
		(pin "99"
		)
		(pin "109"
		)
		(pin "64"
		)
		(pin "66"
		)
		(pin "188"
		)
		(pin "190"
		)
		(pin "192"
		)
		(pin "194"
		)
		(pin "59"
		)
		(pin "87"
		)
		(pin "251"
		)
		(pin "90"
		)
		(pin "92"
		)
		(pin "71"
		)
		(pin "75"
		)
		(pin "119"
		)
		(pin "126"
		)
		(pin "127"
		)
		(pin "1"
		)
		(pin "102"
		)
		(pin "52"
		)
		(pin "54"
		)
		(pin "19"
		)
		(pin "253"
		)
		(pin "260"
		)
		(pin "230"
		)
		(pin "151"
		)
		(pin "154"
		)
		(pin "247"
		)
		(pin "67"
		)
		(pin "243"
		)
		(pin "155"
		)
		(pin "156"
		)
		(pin "20"
		)
		(pin "208"
		)
		(pin "242"
		)
		(pin "231"
		)
		(pin "14"
		)
		(pin "241"
		)
		(pin "78"
		)
		(pin "132"
		)
		(pin "18"
		)
		(pin "240"
		)
		(pin "171"
		)
		(pin "170"
		)
		(pin "153"
		)
		(pin "49"
		)
		(pin "178"
		)
		(pin "226"
		)
		(pin "232"
		)
		(pin "176"
		)
		(pin "185"
		)
		(pin "9"
		)
		(pin "152"
		)
		(pin "101"
		)
		(pin "143"
		)
		(pin "165"
		)
		(pin "257"
		)
		(pin "103"
		)
		(pin "85"
		)
		(pin "259"
		)
		(pin "104"
		)
		(pin "146"
		)
		(pin "220"
		)
		(pin "246"
		)
		(pin "180"
		)
		(pin "181"
		)
		(pin "105"
		)
		(pin "210"
		)
		(pin "254"
		)
		(pin "256"
		)
		(pin "118"
		)
		(pin "124"
		)
		(pin "217"
		)
		(pin "214"
		)
		(pin "255"
		)
		(pin "30"
		)
		(pin "111"
		)
		(pin "115"
		)
		(pin "258"
		)
		(pin "213"
		)
		(pin "82"
		)
		(pin "129"
		)
		(pin "144"
		)
		(pin "128"
		)
		(pin "130"
		)
		(pin "61"
		)
		(pin "79"
		)
		(pin "26"
		)
		(pin "215"
		)
		(pin "33"
		)
		(pin "13"
		)
		(pin "22"
		)
		(pin "62"
		)
		(pin "113"
		)
		(pin "187"
		)
		(pin "177"
		)
		(pin "125"
		)
		(pin "80"
		)
		(pin "8"
		)
		(pin "234"
		)
		(pin "236"
		)
		(pin "238"
		)
		(pin "89"
		)
		(pin "91"
		)
		(pin "93"
		)
		(pin "95"
		)
		(pin "97"
		)
		(pin "222"
		)
		(pin "224"
		)
		(pin "44"
		)
		(pin "135"
		)
		(pin "206"
		)
		(pin "211"
		)
		(pin "86"
		)
		(pin "108"
		)
		(pin "34"
		)
		(pin "218"
		)
		(pin "228"
		)
		(pin "47"
		)
		(pin "51"
		)
		(pin "262"
		)
		(pin "11"
		)
		(pin "203"
		)
		(pin "41"
		)
		(pin "45"
		)
		(pin "123"
		)
		(pin "161"
		)
		(pin "173"
		)
		(pin "174"
		)
		(pin "23"
		)
		(pin "24"
		)
		(pin "55"
		)
		(pin "28"
		)
		(pin "191"
		)
		(pin "27"
		)
		(pin "46"
		)
		(pin "48"
		)
		(pin "163"
		)
		(pin "166"
		)
		(pin "193"
		)
		(pin "195"
		)
		(pin "235"
		)
		(pin "110"
		)
		(pin "237"
		)
		(pin "58"
		)
		(pin "60"
		)
		(pin "175"
		)
		(pin "179"
		)
		(pin "162"
		)
		(pin "167"
		)
		(pin "145"
		)
		(pin "249"
		)
		(pin "157"
		)
		(pin "160"
		)
		(pin "189"
		)
		(pin "239"
		)
		(pin "38"
		)
		(pin "112"
		)
		(pin "5"
		)
		(pin "106"
		)
		(pin "244"
		)
		(pin "149"
		)
		(pin "150"
		)
		(pin "76"
		)
		(pin "94"
		)
		(pin "96"
		)
		(pin "196"
		)
		(pin "198"
		)
		(pin "98"
		)
		(pin "131"
		)
		(pin "116"
		)
		(pin "138"
		)
		(pin "32"
		)
		(pin "200"
		)
		(pin "56"
		)
		(instances
			(project "jetson-orin-baseboard"
				(path ""
					(reference "J15")
					(unit 4)
				)
			)
		)
	)
	(symbol
		(lib_name "R_0R_0402_1")
		(lib_id "antmicroResistors0402:R_0R_0402")
		(at 74.93 57.15 0)
		(unit 1)
		(exclude_from_sim no)
		(in_bom yes)
		(on_board yes)
		(dnp no)
		(property "Reference" "R3"
			(at 80.01 56.515 0)
			(effects
				(font
					(size 1.27 1.27)
				)
				(justify left bottom)
			)
		)
		(property "Value" "R_0R_0402"
			(at 95.25 69.85 0)
			(effects
				(font
					(size 1.27 1.27)
					(thickness 0.15)
				)
				(justify left bottom)
				(hide yes)
			)
		)
		(property "Footprint" "antmicro-footprints:R_0402_1005Metric"
			(at 95.25 72.39 0)
			(effects
				(font
					(size 1.27 1.27)
					(thickness 0.15)
				)
				(justify left bottom)
				(hide yes)
			)
		)
		(property "Datasheet" "https://industrial.panasonic.com/cdbs/www-data/pdf/RDA0000/AOA0000C301.pdf"
			(at 95.25 74.93 0)
			(effects
				(font
					(size 1.27 1.27)
					(thickness 0.15)
				)
				(justify left bottom)
				(hide yes)
			)
		)
		(property "Description" ""
			(at 74.93 57.15 0)
			(effects
				(font
					(size 1.27 1.27)
				)
				(hide yes)
			)
		)
		(property "Manufacturer" "Panasonic"
			(at 95.25 80.01 0)
			(effects
				(font
					(size 1.27 1.27)
					(thickness 0.15)
				)
				(justify left bottom)
				(hide yes)
			)
		)
		(property "MPN" "ERJ2GE0R00X"
			(at 95.25 77.47 0)
			(effects
				(font
					(size 1.27 1.27)
					(thickness 0.15)
				)
				(justify left bottom)
				(hide yes)
			)
		)
		(property "Val" "0R"
			(at 72.39 56.515 0)
			(effects
				(font
					(size 1.27 1.27)
					(thickness 0.15)
				)
				(justify left bottom)
			)
		)
		(property "License" "Apache-2.0"
			(at 95.25 82.55 0)
			(effects
				(font
					(size 1.27 1.27)
					(thickness 0.15)
				)
				(justify left bottom)
				(hide yes)
			)
		)
		(property "Author" "Antmicro"
			(at 95.25 85.09 0)
			(effects
				(font
					(size 1.27 1.27)
					(thickness 0.15)
				)
				(justify left bottom)
				(hide yes)
			)
		)
		(property "Tolerance" "~"
			(at 95.25 67.31 0)
			(effects
				(font
					(size 1.27 1.27)
				)
				(justify left bottom)
				(hide yes)
			)
		)
		(property "Current" "1A"
			(at 95.25 87.63 0)
			(effects
				(font
					(size 1.27 1.27)
					(thickness 0.15)
				)
				(justify left bottom)
				(hide yes)
			)
		)
		(pin "1"
		)
		(pin "2"
		)
		(instances
			(project "jetson-orin-baseboard"
				(path ""
					(reference "R3")
					(unit 1)
				)
			)
		)
	)
	(symbol
		(lib_name "R_0R_0402_2")
		(lib_id "antmicroResistors0402:R_0R_0402")
		(at 74.93 31.75 0)
		(unit 1)
		(exclude_from_sim no)
		(in_bom yes)
		(on_board yes)
		(dnp no)
		(property "Reference" "R1"
			(at 80.01 31.115 0)
			(effects
				(font
					(size 1.27 1.27)
				)
				(justify left bottom)
			)
		)
		(property "Value" "R_0R_0402"
			(at 95.25 44.45 0)
			(effects
				(font
					(size 1.27 1.27)
					(thickness 0.15)
				)
				(justify left bottom)
				(hide yes)
			)
		)
		(property "Footprint" "antmicro-footprints:R_0402_1005Metric"
			(at 95.25 46.99 0)
			(effects
				(font
					(size 1.27 1.27)
					(thickness 0.15)
				)
				(justify left bottom)
				(hide yes)
			)
		)
		(property "Datasheet" "https://industrial.panasonic.com/cdbs/www-data/pdf/RDA0000/AOA0000C301.pdf"
			(at 95.25 49.53 0)
			(effects
				(font
					(size 1.27 1.27)
					(thickness 0.15)
				)
				(justify left bottom)
				(hide yes)
			)
		)
		(property "Description" ""
			(at 74.93 31.75 0)
			(effects
				(font
					(size 1.27 1.27)
				)
				(hide yes)
			)
		)
		(property "Manufacturer" "Panasonic"
			(at 95.25 54.61 0)
			(effects
				(font
					(size 1.27 1.27)
					(thickness 0.15)
				)
				(justify left bottom)
				(hide yes)
			)
		)
		(property "MPN" "ERJ2GE0R00X"
			(at 95.25 52.07 0)
			(effects
				(font
					(size 1.27 1.27)
					(thickness 0.15)
				)
				(justify left bottom)
				(hide yes)
			)
		)
		(property "Val" "0R"
			(at 72.39 31.115 0)
			(effects
				(font
					(size 1.27 1.27)
					(thickness 0.15)
				)
				(justify left bottom)
			)
		)
		(property "License" "Apache-2.0"
			(at 95.25 57.15 0)
			(effects
				(font
					(size 1.27 1.27)
					(thickness 0.15)
				)
				(justify left bottom)
				(hide yes)
			)
		)
		(property "Author" "Antmicro"
			(at 95.25 59.69 0)
			(effects
				(font
					(size 1.27 1.27)
					(thickness 0.15)
				)
				(justify left bottom)
				(hide yes)
			)
		)
		(property "Tolerance" "~"
			(at 95.25 41.91 0)
			(effects
				(font
					(size 1.27 1.27)
				)
				(justify left bottom)
				(hide yes)
			)
		)
		(property "Current" "1A"
			(at 95.25 62.23 0)
			(effects
				(font
					(size 1.27 1.27)
					(thickness 0.15)
				)
				(justify left bottom)
				(hide yes)
			)
		)
		(pin "1"
		)
		(pin "2"
		)
		(instances
			(project "jetson-orin-baseboard"
				(path ""
					(reference "R1")
					(unit 1)
				)
			)
		)
	)
	(symbol
		(lib_name "TP_0.75mm_SMD_1")
		(lib_id "antmicroTestPoints:TP_0.75mm_SMD")
		(at 118.11 156.21 0)
		(unit 1)
		(exclude_from_sim no)
		(in_bom no)
		(on_board yes)
		(dnp no)
		(property "Reference" "TP3"
			(at 121.92 156.21 0)
			(effects
				(font
					(size 1.27 1.27)
				)
				(justify left)
			)
		)
		(property "Value" "TP_0.75mm_SMD"
			(at 128.27 160.02 0)
			(effects
				(font
					(size 1.27 1.27)
					(thickness 0.15)
				)
				(justify left bottom)
				(hide yes)
			)
		)
		(property "Footprint" "antmicro-footprints:TP_SMD_0.75mm"
			(at 128.27 162.56 0)
			(effects
				(font
					(size 1.27 1.27)
					(thickness 0.15)
				)
				(justify left bottom)
				(hide yes)
			)
		)
		(property "Datasheet" ""
			(at 135.89 168.91 0)
			(effects
				(font
					(size 1.27 1.27)
					(thickness 0.15)
				)
				(justify left bottom)
				(hide yes)
			)
		)
		(property "Description" ""
			(at 118.11 156.21 0)
			(effects
				(font
					(size 1.27 1.27)
				)
				(hide yes)
			)
		)
		(property "MPN" ""
			(at 128.905 167.64 0)
			(effects
				(font
					(size 1.27 1.27)
					(thickness 0.15)
				)
				(justify left bottom)
				(hide yes)
			)
		)
		(property "Manufacturer" ""
			(at 128.905 162.56 0)
			(effects
				(font
					(size 1.27 1.27)
					(thickness 0.15)
				)
				(justify left bottom)
				(hide yes)
			)
		)
		(property "Author" "Antmicro"
			(at 128.27 165.1 0)
			(effects
				(font
					(size 1.27 1.27)
					(thickness 0.15)
				)
				(justify left bottom)
				(hide yes)
			)
		)
		(property "License" "Apache-2.0"
			(at 128.27 167.64 0)
			(effects
				(font
					(size 1.27 1.27)
					(thickness 0.15)
				)
				(justify left bottom)
				(hide yes)
			)
		)
		(pin "1"
		)
		(instances
			(project "jetson-orin-baseboard"
				(path ""
					(reference "TP3")
					(unit 1)
				)
			)
		)
	)
	(symbol
		(lib_id "antmicroResistors0402:R_0R_0402")
		(at 281.94 116.84 0)
		(unit 1)
		(exclude_from_sim no)
		(in_bom yes)
		(on_board yes)
		(dnp no)
		(property "Reference" "R12"
			(at 287.02 116.205 0)
			(effects
				(font
					(size 1.27 1.27)
				)
				(justify left bottom)
			)
		)
		(property "Value" "R_0R_0402"
			(at 302.26 129.54 0)
			(effects
				(font
					(size 1.27 1.27)
					(thickness 0.15)
				)
				(justify left bottom)
				(hide yes)
			)
		)
		(property "Footprint" "antmicro-footprints:R_0402_1005Metric"
			(at 302.26 132.08 0)
			(effects
				(font
					(size 1.27 1.27)
					(thickness 0.15)
				)
				(justify left bottom)
				(hide yes)
			)
		)
		(property "Datasheet" "https://industrial.panasonic.com/cdbs/www-data/pdf/RDA0000/AOA0000C301.pdf"
			(at 302.26 134.62 0)
			(effects
				(font
					(size 1.27 1.27)
					(thickness 0.15)
				)
				(justify left bottom)
				(hide yes)
			)
		)
		(property "Description" ""
			(at 281.94 116.84 0)
			(effects
				(font
					(size 1.27 1.27)
				)
				(hide yes)
			)
		)
		(property "Manufacturer" "Panasonic"
			(at 302.26 139.7 0)
			(effects
				(font
					(size 1.27 1.27)
					(thickness 0.15)
				)
				(justify left bottom)
				(hide yes)
			)
		)
		(property "MPN" "ERJ2GE0R00X"
			(at 302.26 137.16 0)
			(effects
				(font
					(size 1.27 1.27)
					(thickness 0.15)
				)
				(justify left bottom)
				(hide yes)
			)
		)
		(property "Val" "0R"
			(at 279.4 116.205 0)
			(effects
				(font
					(size 1.27 1.27)
					(thickness 0.15)
				)
				(justify left bottom)
			)
		)
		(property "License" "Apache-2.0"
			(at 302.26 142.24 0)
			(effects
				(font
					(size 1.27 1.27)
					(thickness 0.15)
				)
				(justify left bottom)
				(hide yes)
			)
		)
		(property "Author" "Antmicro"
			(at 302.26 144.78 0)
			(effects
				(font
					(size 1.27 1.27)
					(thickness 0.15)
				)
				(justify left bottom)
				(hide yes)
			)
		)
		(property "Tolerance" "~"
			(at 302.26 127 0)
			(effects
				(font
					(size 1.27 1.27)
				)
				(justify left bottom)
				(hide yes)
			)
		)
		(property "Current" "1A"
			(at 302.26 147.32 0)
			(effects
				(font
					(size 1.27 1.27)
					(thickness 0.15)
				)
				(justify left bottom)
				(hide yes)
			)
		)
		(pin "1"
		)
		(pin "2"
		)
		(instances
			(project "jetson-orin-baseboard"
				(path ""
					(reference "R12")
					(unit 1)
				)
			)
		)
	)
	(symbol
		(lib_name "GND_4")
		(lib_id "antmicropower:GND")
		(at 87.63 259.08 0)
		(unit 1)
		(exclude_from_sim no)
		(in_bom yes)
		(on_board yes)
		(dnp no)
		(property "Reference" "#PWR0151"
			(at 87.63 265.43 0)
			(effects
				(font
					(size 1.27 1.27)
				)
				(justify left bottom)
				(hide yes)
			)
		)
		(property "Value" "GND"
			(at 87.63 262.89 0)
			(effects
				(font
					(size 1.27 1.27)
					(thickness 0.15)
				)
			)
		)
		(property "Footprint" ""
			(at 96.52 266.7 0)
			(effects
				(font
					(size 1.27 1.27)
					(thickness 0.15)
				)
				(justify left bottom)
				(hide yes)
			)
		)
		(property "Datasheet" ""
			(at 96.52 271.78 0)
			(effects
				(font
					(size 1.27 1.27)
					(thickness 0.15)
				)
				(justify left bottom)
				(hide yes)
			)
		)
		(property "Description" ""
			(at 87.63 259.08 0)
			(effects
				(font
					(size 1.27 1.27)
				)
				(hide yes)
			)
		)
		(property "Author" "Antmicro"
			(at 96.52 266.7 0)
			(effects
				(font
					(size 1.27 1.27)
					(thickness 0.15)
				)
				(justify left bottom)
				(hide yes)
			)
		)
		(property "License" "Apache-2.0"
			(at 96.52 269.24 0)
			(effects
				(font
					(size 1.27 1.27)
					(thickness 0.15)
				)
				(justify left bottom)
				(hide yes)
			)
		)
		(pin "1"
		)
		(instances
			(project "jetson-orin-baseboard"
				(path ""
					(reference "#PWR0151")
					(unit 1)
				)
			)
		)
	)
	(symbol
		(lib_name "+1V8_1")
		(lib_id "antmicropower:+1V8")
		(at 115.57 40.64 0)
		(unit 1)
		(exclude_from_sim no)
		(in_bom yes)
		(on_board yes)
		(dnp no)
		(property "Reference" "#PWR0275"
			(at 115.57 44.45 0)
			(effects
				(font
					(size 1.27 1.27)
				)
				(justify left bottom)
				(hide yes)
			)
		)
		(property "Value" "+1V8"
			(at 112.395 37.465 0)
			(effects
				(font
					(size 1.27 1.27)
					(thickness 0.15)
				)
				(justify left bottom)
			)
		)
		(property "Footprint" ""
			(at 130.81 48.26 0)
			(effects
				(font
					(size 1.27 1.27)
					(thickness 0.15)
				)
				(justify left bottom)
				(hide yes)
			)
		)
		(property "Datasheet" ""
			(at 130.81 50.8 0)
			(effects
				(font
					(size 1.27 1.27)
					(thickness 0.15)
				)
				(justify left bottom)
				(hide yes)
			)
		)
		(property "Description" ""
			(at 115.57 40.64 0)
			(effects
				(font
					(size 1.27 1.27)
				)
				(hide yes)
			)
		)
		(property "Author" "Antmicro"
			(at 130.81 45.72 0)
			(effects
				(font
					(size 1.27 1.27)
					(thickness 0.15)
				)
				(justify left bottom)
				(hide yes)
			)
		)
		(property "License" "Apache-2.0"
			(at 130.81 48.26 0)
			(effects
				(font
					(size 1.27 1.27)
					(thickness 0.15)
				)
				(justify left bottom)
				(hide yes)
			)
		)
		(pin "1"
		)
		(instances
			(project "jetson-orin-baseboard"
				(path ""
					(reference "#PWR0275")
					(unit 1)
				)
			)
		)
	)
	(symbol
		(lib_id "antmicroResistors0402:R_2k2_0402")
		(at 41.91 152.4 90)
		(unit 1)
		(exclude_from_sim no)
		(in_bom yes)
		(on_board yes)
		(dnp no)
		(property "Reference" "R294"
			(at 43.18 148.59 90)
			(effects
				(font
					(size 1.27 1.27)
				)
				(justify right)
			)
		)
		(property "Value" "R_2k2_0402"
			(at 54.61 132.08 0)
			(effects
				(font
					(size 1.27 1.27)
					(thickness 0.15)
				)
				(justify left bottom)
				(hide yes)
			)
		)
		(property "Footprint" "antmicro-footprints:R_0402_1005Metric"
			(at 57.15 132.08 0)
			(effects
				(font
					(size 1.27 1.27)
					(thickness 0.15)
				)
				(justify left bottom)
				(hide yes)
			)
		)
		(property "Datasheet" "https://www.bourns.com/docs/product-datasheets/cr.pdf"
			(at 59.69 132.08 0)
			(effects
				(font
					(size 1.27 1.27)
					(thickness 0.15)
				)
				(justify left bottom)
				(hide yes)
			)
		)
		(property "Description" ""
			(at 41.91 152.4 0)
			(effects
				(font
					(size 1.27 1.27)
				)
				(hide yes)
			)
		)
		(property "Manufacturer" "Bourns"
			(at 64.77 132.08 0)
			(effects
				(font
					(size 1.27 1.27)
					(thickness 0.15)
				)
				(justify left bottom)
				(hide yes)
			)
		)
		(property "MPN" "CR0402-FX-2201GLF"
			(at 62.23 132.08 0)
			(effects
				(font
					(size 1.27 1.27)
					(thickness 0.15)
				)
				(justify left bottom)
				(hide yes)
			)
		)
		(property "Val" "2k2"
			(at 43.18 151.13 90)
			(effects
				(font
					(size 1.27 1.27)
					(thickness 0.15)
				)
				(justify right)
			)
		)
		(property "License" "Apache-2.0"
			(at 67.31 132.08 0)
			(effects
				(font
					(size 1.27 1.27)
					(thickness 0.15)
				)
				(justify left bottom)
				(hide yes)
			)
		)
		(property "Author" "Antmicro"
			(at 69.85 132.08 0)
			(effects
				(font
					(size 1.27 1.27)
					(thickness 0.15)
				)
				(justify left bottom)
				(hide yes)
			)
		)
		(property "Tolerance" "1%"
			(at 52.07 132.08 0)
			(effects
				(font
					(size 1.27 1.27)
				)
				(justify left bottom)
				(hide yes)
			)
		)
		(pin "1"
		)
		(pin "2"
		)
		(instances
			(project "jetson-orin-baseboard"
				(path ""
					(reference "R294")
					(unit 1)
				)
			)
		)
	)
	(symbol
		(lib_name "R_0R_0402_3")
		(lib_id "antmicroResistors0402:R_0R_0402")
		(at 74.93 54.61 0)
		(unit 1)
		(exclude_from_sim no)
		(in_bom yes)
		(on_board yes)
		(dnp no)
		(property "Reference" "R2"
			(at 80.01 53.975 0)
			(effects
				(font
					(size 1.27 1.27)
				)
				(justify left bottom)
			)
		)
		(property "Value" "R_0R_0402"
			(at 95.25 67.31 0)
			(effects
				(font
					(size 1.27 1.27)
					(thickness 0.15)
				)
				(justify left bottom)
				(hide yes)
			)
		)
		(property "Footprint" "antmicro-footprints:R_0402_1005Metric"
			(at 95.25 69.85 0)
			(effects
				(font
					(size 1.27 1.27)
					(thickness 0.15)
				)
				(justify left bottom)
				(hide yes)
			)
		)
		(property "Datasheet" "https://industrial.panasonic.com/cdbs/www-data/pdf/RDA0000/AOA0000C301.pdf"
			(at 95.25 72.39 0)
			(effects
				(font
					(size 1.27 1.27)
					(thickness 0.15)
				)
				(justify left bottom)
				(hide yes)
			)
		)
		(property "Description" ""
			(at 74.93 54.61 0)
			(effects
				(font
					(size 1.27 1.27)
				)
				(hide yes)
			)
		)
		(property "Manufacturer" "Panasonic"
			(at 95.25 77.47 0)
			(effects
				(font
					(size 1.27 1.27)
					(thickness 0.15)
				)
				(justify left bottom)
				(hide yes)
			)
		)
		(property "MPN" "ERJ2GE0R00X"
			(at 95.25 74.93 0)
			(effects
				(font
					(size 1.27 1.27)
					(thickness 0.15)
				)
				(justify left bottom)
				(hide yes)
			)
		)
		(property "Val" "0R"
			(at 72.39 53.975 0)
			(effects
				(font
					(size 1.27 1.27)
					(thickness 0.15)
				)
				(justify left bottom)
			)
		)
		(property "License" "Apache-2.0"
			(at 95.25 80.01 0)
			(effects
				(font
					(size 1.27 1.27)
					(thickness 0.15)
				)
				(justify left bottom)
				(hide yes)
			)
		)
		(property "Author" "Antmicro"
			(at 95.25 82.55 0)
			(effects
				(font
					(size 1.27 1.27)
					(thickness 0.15)
				)
				(justify left bottom)
				(hide yes)
			)
		)
		(property "Tolerance" "~"
			(at 95.25 64.77 0)
			(effects
				(font
					(size 1.27 1.27)
				)
				(justify left bottom)
				(hide yes)
			)
		)
		(property "Current" "1A"
			(at 95.25 85.09 0)
			(effects
				(font
					(size 1.27 1.27)
					(thickness 0.15)
				)
				(justify left bottom)
				(hide yes)
			)
		)
		(pin "1"
		)
		(pin "2"
		)
		(instances
			(project "jetson-orin-baseboard"
				(path ""
					(reference "R2")
					(unit 1)
				)
			)
		)
	)
	(symbol
		(lib_id "antmicroResistors0402:R_4k7_0402")
		(at 115.57 46.99 90)
		(unit 1)
		(exclude_from_sim no)
		(in_bom yes)
		(on_board yes)
		(dnp no)
		(property "Reference" "R80"
			(at 116.84 43.18 90)
			(effects
				(font
					(size 1.27 1.27)
				)
				(justify right)
			)
		)
		(property "Value" "R_4k7_0402"
			(at 128.27 26.67 0)
			(effects
				(font
					(size 1.27 1.27)
					(thickness 0.15)
				)
				(justify left bottom)
				(hide yes)
			)
		)
		(property "Footprint" "antmicro-footprints:R_0402_1005Metric"
			(at 130.81 26.67 0)
			(effects
				(font
					(size 1.27 1.27)
					(thickness 0.15)
				)
				(justify left bottom)
				(hide yes)
			)
		)
		(property "Datasheet" "https://www.bourns.com/docs/product-datasheets/cr.pdf"
			(at 133.35 26.67 0)
			(effects
				(font
					(size 1.27 1.27)
					(thickness 0.15)
				)
				(justify left bottom)
				(hide yes)
			)
		)
		(property "Description" ""
			(at 115.57 46.99 0)
			(effects
				(font
					(size 1.27 1.27)
				)
				(hide yes)
			)
		)
		(property "Manufacturer" "Bourns"
			(at 138.43 26.67 0)
			(effects
				(font
					(size 1.27 1.27)
					(thickness 0.15)
				)
				(justify left bottom)
				(hide yes)
			)
		)
		(property "MPN" "CR0402-FX-4701GLF"
			(at 135.89 26.67 0)
			(effects
				(font
					(size 1.27 1.27)
					(thickness 0.15)
				)
				(justify left bottom)
				(hide yes)
			)
		)
		(property "Val" "4k7"
			(at 116.84 45.72 90)
			(effects
				(font
					(size 1.27 1.27)
					(thickness 0.15)
				)
				(justify right)
			)
		)
		(property "License" "Apache-2.0"
			(at 140.97 26.67 0)
			(effects
				(font
					(size 1.27 1.27)
					(thickness 0.15)
				)
				(justify left bottom)
				(hide yes)
			)
		)
		(property "Author" "Antmicro"
			(at 143.51 26.67 0)
			(effects
				(font
					(size 1.27 1.27)
					(thickness 0.15)
				)
				(justify left bottom)
				(hide yes)
			)
		)
		(property "Tolerance" "1%"
			(at 125.73 26.67 0)
			(effects
				(font
					(size 1.27 1.27)
				)
				(justify left bottom)
				(hide yes)
			)
		)
		(pin "1"
		)
		(pin "2"
		)
		(instances
			(project "jetson-orin-baseboard"
				(path ""
					(reference "R80")
					(unit 1)
				)
			)
		)
	)
	(symbol
		(lib_id "antmicroLogicTranslatorsLevelShifters:NTS0102_XSON")
		(at 66.04 250.19 0)
		(unit 1)
		(exclude_from_sim no)
		(in_bom yes)
		(on_board yes)
		(dnp no)
		(fields_autoplaced yes)
		(property "Reference" "U4"
			(at 76.2 243.205 0)
			(effects
				(font
					(size 1.27 1.27)
				)
			)
		)
		(property "Value" "NTS0102_XSON"
			(at 101.6 257.81 0)
			(effects
				(font
					(size 1.27 1.27)
					(thickness 0.15)
				)
				(justify left bottom)
				(hide yes)
			)
		)
		(property "Footprint" "antmicro-footprints:XSON-8_1x1.95mm_P0.5mm"
			(at 101.6 260.35 0)
			(effects
				(font
					(size 1.27 1.27)
					(thickness 0.15)
				)
				(justify left bottom)
				(hide yes)
			)
		)
		(property "Datasheet" "http://www.farnell.com/datasheets/1760723.pdf"
			(at 101.6 262.89 0)
			(effects
				(font
					(size 1.27 1.27)
					(thickness 0.15)
				)
				(justify left bottom)
				(hide yes)
			)
		)
		(property "Description" ""
			(at 66.04 250.19 0)
			(effects
				(font
					(size 1.27 1.27)
				)
				(hide yes)
			)
		)
		(property "MPN" "NTS0102GT"
			(at 76.2 245.745 0)
			(effects
				(font
					(size 1.27 1.27)
					(thickness 0.15)
				)
			)
		)
		(property "Manufacturer" "NXP"
			(at 101.6 265.43 0)
			(effects
				(font
					(size 1.27 1.27)
					(thickness 0.15)
				)
				(justify left bottom)
				(hide yes)
			)
		)
		(property "Author" "Antmicro"
			(at 101.6 267.97 0)
			(effects
				(font
					(size 1.27 1.27)
					(thickness 0.15)
				)
				(justify left bottom)
				(hide yes)
			)
		)
		(property "License" "Apache-2.0"
			(at 101.6 270.51 0)
			(effects
				(font
					(size 1.27 1.27)
					(thickness 0.15)
				)
				(justify left bottom)
				(hide yes)
			)
		)
		(pin "1"
		)
		(pin "2"
		)
		(pin "3"
		)
		(pin "4"
		)
		(pin "5"
		)
		(pin "6"
		)
		(pin "7"
		)
		(pin "8"
		)
		(instances
			(project "jetson-orin-baseboard"
				(path ""
					(reference "U4")
					(unit 1)
				)
			)
		)
	)
	(symbol
		(lib_id "antmicroTVSDiodes:TPD1E0B04_XDFN-2")
		(at 105.41 172.72 90)
		(unit 1)
		(exclude_from_sim no)
		(in_bom yes)
		(on_board yes)
		(dnp no)
		(property "Reference" "D55"
			(at 103.505 168.91 90)
			(effects
				(font
					(size 1.27 1.27)
				)
				(justify left)
			)
		)
		(property "Value" "TPD1E0B04_XDFN-2"
			(at 115.57 157.48 0)
			(effects
				(font
					(size 1.27 1.27)
					(thickness 0.15)
				)
				(justify left bottom)
				(hide yes)
			)
		)
		(property "Footprint" "antmicro-footprints:XDFN-2_1x0.60mm"
			(at 110.49 157.48 0)
			(effects
				(font
					(size 1.27 1.27)
					(thickness 0.15)
				)
				(justify left bottom)
				(hide yes)
			)
		)
		(property "Datasheet" "https://www.ti.com/general/docs/suppproductinfo.tsp?distId=26&gotoUrl=https://www.ti.com/lit/gpn/tpd1e0b04"
			(at 113.03 157.48 0)
			(effects
				(font
					(size 1.27 1.27)
					(thickness 0.15)
				)
				(justify left bottom)
				(hide yes)
			)
		)
		(property "Description" ""
			(at 105.41 172.72 0)
			(effects
				(font
					(size 1.27 1.27)
				)
				(hide yes)
			)
		)
		(property "Manufacturer" "Texas Instruments"
			(at 118.11 157.48 0)
			(effects
				(font
					(size 1.27 1.27)
					(thickness 0.15)
				)
				(justify left bottom)
				(hide yes)
			)
		)
		(property "MPN" "TPD1E0B04DPYR"
			(at 103.505 171.45 90)
			(effects
				(font
					(size 1.27 1.27)
					(thickness 0.15)
				)
				(justify left)
			)
		)
		(property "Author" "Antmicro"
			(at 120.65 157.48 0)
			(effects
				(font
					(size 1.27 1.27)
					(thickness 0.15)
				)
				(justify left bottom)
				(hide yes)
			)
		)
		(property "License" "Apache-2.0"
			(at 123.19 157.48 0)
			(effects
				(font
					(size 1.27 1.27)
					(thickness 0.15)
				)
				(justify left bottom)
				(hide yes)
			)
		)
		(pin "1"
		)
		(pin "2"
		)
		(instances
			(project "jetson-orin-baseboard"
				(path ""
					(reference "D55")
					(unit 1)
				)
			)
		)
	)
	(symbol
		(lib_name "TP_0.75mm_SMD_3")
		(lib_id "antmicroTestPoints:TP_0.75mm_SMD")
		(at 118.11 153.67 0)
		(unit 1)
		(exclude_from_sim no)
		(in_bom no)
		(on_board yes)
		(dnp no)
		(property "Reference" "TP2"
			(at 121.92 153.67 0)
			(effects
				(font
					(size 1.27 1.27)
				)
				(justify left)
			)
		)
		(property "Value" "TP_0.75mm_SMD"
			(at 128.27 157.48 0)
			(effects
				(font
					(size 1.27 1.27)
					(thickness 0.15)
				)
				(justify left bottom)
				(hide yes)
			)
		)
		(property "Footprint" "antmicro-footprints:TP_SMD_0.75mm"
			(at 128.27 160.02 0)
			(effects
				(font
					(size 1.27 1.27)
					(thickness 0.15)
				)
				(justify left bottom)
				(hide yes)
			)
		)
		(property "Datasheet" ""
			(at 135.89 166.37 0)
			(effects
				(font
					(size 1.27 1.27)
					(thickness 0.15)
				)
				(justify left bottom)
				(hide yes)
			)
		)
		(property "Description" ""
			(at 118.11 153.67 0)
			(effects
				(font
					(size 1.27 1.27)
				)
				(hide yes)
			)
		)
		(property "MPN" ""
			(at 128.905 165.1 0)
			(effects
				(font
					(size 1.27 1.27)
					(thickness 0.15)
				)
				(justify left bottom)
				(hide yes)
			)
		)
		(property "Manufacturer" ""
			(at 128.905 160.02 0)
			(effects
				(font
					(size 1.27 1.27)
					(thickness 0.15)
				)
				(justify left bottom)
				(hide yes)
			)
		)
		(property "Author" "Antmicro"
			(at 128.27 162.56 0)
			(effects
				(font
					(size 1.27 1.27)
					(thickness 0.15)
				)
				(justify left bottom)
				(hide yes)
			)
		)
		(property "License" "Apache-2.0"
			(at 128.27 165.1 0)
			(effects
				(font
					(size 1.27 1.27)
					(thickness 0.15)
				)
				(justify left bottom)
				(hide yes)
			)
		)
		(pin "1"
		)
		(instances
			(project "jetson-orin-baseboard"
				(path ""
					(reference "TP2")
					(unit 1)
				)
			)
		)
	)
	(symbol
		(lib_name "GND_3")
		(lib_id "antmicropower:GND")
		(at 38.1 116.84 0)
		(unit 1)
		(exclude_from_sim no)
		(in_bom yes)
		(on_board yes)
		(dnp no)
		(property "Reference" "#PWR06"
			(at 38.1 123.19 0)
			(effects
				(font
					(size 1.27 1.27)
				)
				(justify left bottom)
				(hide yes)
			)
		)
		(property "Value" "GND"
			(at 38.1 120.65 0)
			(effects
				(font
					(size 1.27 1.27)
					(thickness 0.15)
				)
				(hide yes)
			)
		)
		(property "Footprint" ""
			(at 46.99 124.46 0)
			(effects
				(font
					(size 1.27 1.27)
					(thickness 0.15)
				)
				(justify left bottom)
				(hide yes)
			)
		)
		(property "Datasheet" ""
			(at 46.99 129.54 0)
			(effects
				(font
					(size 1.27 1.27)
					(thickness 0.15)
				)
				(justify left bottom)
				(hide yes)
			)
		)
		(property "Description" ""
			(at 38.1 116.84 0)
			(effects
				(font
					(size 1.27 1.27)
				)
				(hide yes)
			)
		)
		(property "Author" "Antmicro"
			(at 46.99 124.46 0)
			(effects
				(font
					(size 1.27 1.27)
					(thickness 0.15)
				)
				(justify left bottom)
				(hide yes)
			)
		)
		(property "License" "Apache-2.0"
			(at 46.99 127 0)
			(effects
				(font
					(size 1.27 1.27)
					(thickness 0.15)
				)
				(justify left bottom)
				(hide yes)
			)
		)
		(pin "1"
		)
		(instances
			(project "jetson-orin-baseboard"
				(path ""
					(reference "#PWR06")
					(unit 1)
				)
			)
		)
	)
	(symbol
		(lib_name "GND_8")
		(lib_id "antmicropower:GND")
		(at 41.91 165.1 0)
		(mirror y)
		(unit 1)
		(exclude_from_sim no)
		(in_bom yes)
		(on_board yes)
		(dnp no)
		(property "Reference" "#PWR0313"
			(at 41.91 171.45 0)
			(effects
				(font
					(size 1.27 1.27)
				)
				(justify left bottom)
				(hide yes)
			)
		)
		(property "Value" "GND"
			(at 41.91 168.91 0)
			(effects
				(font
					(size 1.27 1.27)
					(thickness 0.15)
				)
			)
		)
		(property "Footprint" ""
			(at 33.02 172.72 0)
			(effects
				(font
					(size 1.27 1.27)
					(thickness 0.15)
				)
				(justify left bottom)
				(hide yes)
			)
		)
		(property "Datasheet" ""
			(at 33.02 177.8 0)
			(effects
				(font
					(size 1.27 1.27)
					(thickness 0.15)
				)
				(justify left bottom)
				(hide yes)
			)
		)
		(property "Description" ""
			(at 41.91 165.1 0)
			(effects
				(font
					(size 1.27 1.27)
				)
				(hide yes)
			)
		)
		(property "Author" "Antmicro"
			(at 33.02 172.72 0)
			(effects
				(font
					(size 1.27 1.27)
					(thickness 0.15)
				)
				(justify left bottom)
				(hide yes)
			)
		)
		(property "License" "Apache-2.0"
			(at 33.02 175.26 0)
			(effects
				(font
					(size 1.27 1.27)
					(thickness 0.15)
				)
				(justify left bottom)
				(hide yes)
			)
		)
		(pin "1"
		)
		(instances
			(project "jetson-orin-baseboard"
				(path ""
					(reference "#PWR0313")
					(unit 1)
				)
			)
		)
	)
	(symbol
		(lib_name "R_0R_0402_5")
		(lib_id "antmicroResistors0402:R_0R_0402")
		(at 74.93 60.96 0)
		(unit 1)
		(exclude_from_sim no)
		(in_bom no)
		(on_board yes)
		(dnp yes)
		(property "Reference" "R4"
			(at 80.01 60.325 0)
			(effects
				(font
					(size 1.27 1.27)
				)
				(justify left bottom)
			)
		)
		(property "Value" "R_0R_0402"
			(at 95.25 73.66 0)
			(effects
				(font
					(size 1.27 1.27)
					(thickness 0.15)
				)
				(justify left bottom)
				(hide yes)
			)
		)
		(property "Footprint" "antmicro-footprints:R_0402_1005Metric"
			(at 95.25 76.2 0)
			(effects
				(font
					(size 1.27 1.27)
					(thickness 0.15)
				)
				(justify left bottom)
				(hide yes)
			)
		)
		(property "Datasheet" "https://industrial.panasonic.com/cdbs/www-data/pdf/RDA0000/AOA0000C301.pdf"
			(at 95.25 78.74 0)
			(effects
				(font
					(size 1.27 1.27)
					(thickness 0.15)
				)
				(justify left bottom)
				(hide yes)
			)
		)
		(property "Description" ""
			(at 74.93 60.96 0)
			(effects
				(font
					(size 1.27 1.27)
				)
				(hide yes)
			)
		)
		(property "Manufacturer" "Panasonic"
			(at 95.25 83.82 0)
			(effects
				(font
					(size 1.27 1.27)
					(thickness 0.15)
				)
				(justify left bottom)
				(hide yes)
			)
		)
		(property "MPN" "ERJ2GE0R00X"
			(at 95.25 81.28 0)
			(effects
				(font
					(size 1.27 1.27)
					(thickness 0.15)
				)
				(justify left bottom)
				(hide yes)
			)
		)
		(property "Val" "0R"
			(at 72.39 60.325 0)
			(effects
				(font
					(size 1.27 1.27)
					(thickness 0.15)
				)
				(justify left bottom)
			)
		)
		(property "License" "Apache-2.0"
			(at 95.25 86.36 0)
			(effects
				(font
					(size 1.27 1.27)
					(thickness 0.15)
				)
				(justify left bottom)
				(hide yes)
			)
		)
		(property "Author" "Antmicro"
			(at 95.25 88.9 0)
			(effects
				(font
					(size 1.27 1.27)
					(thickness 0.15)
				)
				(justify left bottom)
				(hide yes)
			)
		)
		(property "Tolerance" "~"
			(at 95.25 71.12 0)
			(effects
				(font
					(size 1.27 1.27)
				)
				(justify left bottom)
				(hide yes)
			)
		)
		(property "Current" "1A"
			(at 95.25 91.44 0)
			(effects
				(font
					(size 1.27 1.27)
					(thickness 0.15)
				)
				(justify left bottom)
				(hide yes)
			)
		)
		(pin "1"
		)
		(pin "2"
		)
		(instances
			(project "jetson-orin-baseboard"
				(path ""
					(reference "R4")
					(unit 1)
				)
			)
		)
	)
	(symbol
		(lib_id "antmicroCapacitorspol:C_Pol_100u_25V_KEMET-T521-D-107")
		(at 38.1 110.49 270)
		(unit 1)
		(exclude_from_sim no)
		(in_bom yes)
		(on_board yes)
		(dnp no)
		(property "Reference" "C1"
			(at 40.64 111.2266 90)
			(effects
				(font
					(size 1.27 1.27)
					(thickness 0.15)
				)
				(justify left)
			)
		)
		(property "Value" "C_Pol_100u_25V_KEMET-T521-D-107"
			(at 35.56 124.46 0)
			(effects
				(font
					(size 1.27 1.27)
					(thickness 0.15)
				)
				(justify left bottom)
				(hide yes)
			)
		)
		(property "Footprint" "antmicro-footprints:C_Pol_EIA-X"
			(at 30.48 124.46 0)
			(effects
				(font
					(size 1.27 1.27)
					(thickness 0.15)
				)
				(justify left bottom)
				(hide yes)
			)
		)
		(property "Datasheet" "https://content.kemet.com/datasheets/KEM_T2076_T52X-530.pdf"
			(at 27.94 124.46 0)
			(effects
				(font
					(size 1.27 1.27)
					(thickness 0.15)
				)
				(justify left bottom)
				(hide yes)
			)
		)
		(property "Description" "Surface Mount Tantalum Capacitor, 100 µF, 25 V, 2917 [7343 Metric], ± 20%, 0.04 ohm"
			(at 38.1 110.49 0)
			(effects
				(font
					(size 1.27 1.27)
				)
				(hide yes)
			)
		)
		(property "Val" "100u"
			(at 38.862 115.062 90)
			(effects
				(font
					(size 1.27 1.27)
					(thickness 0.15)
				)
				(justify left)
			)
		)
		(property "MPN" "T521D107M025ATE040"
			(at 25.4 124.46 0)
			(effects
				(font
					(size 1.27 1.27)
					(thickness 0.15)
				)
				(justify left bottom)
				(hide yes)
			)
		)
		(property "Manufacturer" "KEMET"
			(at 22.86 124.46 0)
			(effects
				(font
					(size 1.27 1.27)
					(thickness 0.15)
				)
				(justify left bottom)
				(hide yes)
			)
		)
		(property "License" "Apache-2.0"
			(at 20.32 124.46 0)
			(effects
				(font
					(size 1.27 1.27)
					(thickness 0.15)
				)
				(justify left bottom)
				(hide yes)
			)
		)
		(property "Author" "Antmicro"
			(at 17.78 124.46 0)
			(effects
				(font
					(size 1.27 1.27)
					(thickness 0.15)
				)
				(justify left bottom)
				(hide yes)
			)
		)
		(property "Voltage" "25V"
			(at 15.24 124.46 0)
			(effects
				(font
					(size 1.27 1.27)
				)
				(justify left bottom)
				(hide yes)
			)
		)
		(property "Dielectric" "template_dielectric"
			(at 12.7 124.46 0)
			(effects
				(font
					(size 1.27 1.27)
				)
				(justify left bottom)
				(hide yes)
			)
		)
		(pin "1"
		)
		(pin "2"
		)
		(instances
			(project "jetson-orin-baseboard"
				(path ""
					(reference "C1")
					(unit 1)
				)
			)
		)
	)
	(symbol
		(lib_id "antmicroMechanicalParts:Spacer_Drill3.7mm_H6.5mm_9774065151R")
		(at 152.4 273.05 0)
		(unit 1)
		(exclude_from_sim no)
		(in_bom yes)
		(on_board yes)
		(dnp no)
		(fields_autoplaced yes)
		(property "Reference" "H2"
			(at 161.29 271.78 0)
			(effects
				(font
					(size 1.27 1.27)
					(thickness 0.15)
				)
				(justify left)
			)
		)
		(property "Value" "Spacer_Drill3.7mm_H6.5mm_9774065151R"
			(at 167.64 283.21 0)
			(effects
				(font
					(size 1.27 1.27)
					(thickness 0.15)
				)
				(justify left bottom)
				(hide yes)
			)
		)
		(property "Footprint" "antmicro-footprints:Spacer_Drill3.7mm_H6.5mm_9774065151R"
			(at 167.64 285.75 0)
			(effects
				(font
					(size 1.27 1.27)
					(thickness 0.15)
				)
				(justify left bottom)
				(hide yes)
			)
		)
		(property "Datasheet" "https://www.we-online.com/components/products/datasheet/9774065151R.pdf"
			(at 167.64 288.29 0)
			(effects
				(font
					(size 1.27 1.27)
					(thickness 0.15)
				)
				(justify left bottom)
				(hide yes)
			)
		)
		(property "Description" ""
			(at 152.4 273.05 0)
			(effects
				(font
					(size 1.27 1.27)
				)
				(hide yes)
			)
		)
		(property "Manufacturer" "Würth Elektronik"
			(at 167.64 290.83 0)
			(effects
				(font
					(size 1.27 1.27)
					(thickness 0.15)
				)
				(justify left bottom)
				(hide yes)
			)
		)
		(property "MPN" "9774065151R"
			(at 161.29 274.32 0)
			(effects
				(font
					(size 1.27 1.27)
					(thickness 0.15)
				)
				(justify left)
			)
		)
		(property "Author" "Antmicro"
			(at 167.64 293.37 0)
			(effects
				(font
					(size 1.27 1.27)
					(thickness 0.15)
				)
				(justify left bottom)
				(hide yes)
			)
		)
		(property "License" "Apache-2.0"
			(at 167.64 295.91 0)
			(effects
				(font
					(size 1.27 1.27)
					(thickness 0.15)
				)
				(justify left bottom)
				(hide yes)
			)
		)
		(pin "1"
		)
		(instances
			(project "jetson-orin-baseboard"
				(path ""
					(reference "H2")
					(unit 1)
				)
			)
		)
	)
	(symbol
		(lib_id "antmicroResistors0603:R_0R_22.4A_0603")
		(at 29.21 109.22 0)
		(unit 1)
		(exclude_from_sim no)
		(in_bom yes)
		(on_board yes)
		(dnp no)
		(property "Reference" "R287"
			(at 34.29 108.585 0)
			(effects
				(font
					(size 1.27 1.27)
				)
				(justify left bottom)
			)
		)
		(property "Value" "R_0R_22.4A_0603"
			(at 31.75 100.33 0)
			(effects
				(font
					(size 1.27 1.27)
					(thickness 0.15)
				)
				(hide yes)
			)
		)
		(property "Footprint" "antmicro-footprints:R_0603_1608Metric"
			(at 44.45 119.38 0)
			(effects
				(font
					(size 1.27 1.27)
					(thickness 0.15)
				)
				(justify left bottom)
				(hide yes)
			)
		)
		(property "Datasheet" "https://fscdn.rohm.com/en/products/databook/datasheet/passive/resistor/chip_resistor/pmr-jpw-e.pdf"
			(at 44.45 121.92 0)
			(effects
				(font
					(size 1.27 1.27)
					(thickness 0.15)
				)
				(justify left bottom)
				(hide yes)
			)
		)
		(property "Description" ""
			(at 29.21 109.22 0)
			(effects
				(font
					(size 1.27 1.27)
				)
				(hide yes)
			)
		)
		(property "Manufacturer" "ROHM Semiconductor"
			(at 44.45 127 0)
			(effects
				(font
					(size 1.27 1.27)
					(thickness 0.15)
				)
				(justify left bottom)
				(hide yes)
			)
		)
		(property "MPN" "PMR03EZPJ000"
			(at 44.45 124.46 0)
			(effects
				(font
					(size 1.27 1.27)
					(thickness 0.15)
				)
				(justify left bottom)
				(hide yes)
			)
		)
		(property "Val" "0R"
			(at 26.67 108.585 0)
			(effects
				(font
					(size 1.27 1.27)
					(thickness 0.15)
				)
				(justify left bottom)
			)
		)
		(property "Author" "Antmicro"
			(at 44.45 132.08 0)
			(effects
				(font
					(size 1.27 1.27)
					(thickness 0.15)
				)
				(justify left bottom)
				(hide yes)
			)
		)
		(property "License" "Apache-2.0"
			(at 44.45 134.62 0)
			(effects
				(font
					(size 1.27 1.27)
					(thickness 0.15)
				)
				(justify left bottom)
				(hide yes)
			)
		)
		(property "Max. Curr." "22.4A"
			(at 31.75 111.125 0)
			(effects
				(font
					(size 1.27 1.27)
					(thickness 0.15)
				)
			)
		)
		(property "Tolerance" "template_tolerance"
			(at 49.53 119.38 0)
			(effects
				(font
					(size 1.27 1.27)
				)
				(justify left bottom)
				(hide yes)
			)
		)
		(pin "1"
		)
		(pin "2"
		)
		(instances
			(project "jetson-orin-baseboard"
				(path ""
					(reference "R287")
					(unit 1)
				)
			)
		)
	)
	(symbol
		(lib_id "antmicroSoMConnectors:Bus_DDR4_SODIMM_CUSTOM_Jetson-Orin-H9.2mm-socket")
		(at 193.04 39.37 0)
		(mirror y)
		(unit 3)
		(exclude_from_sim no)
		(in_bom yes)
		(on_board yes)
		(dnp no)
		(fields_autoplaced yes)
		(property "Reference" "J15"
			(at 173.355 30.48 0)
			(effects
				(font
					(size 1.27 1.27)
					(thickness 0.15)
				)
			)
		)
		(property "Value" "Bus_DDR4_SODIMM_CUSTOM_Jetson-Orin-H9.2mm-socket"
			(at 130.81 46.99 0)
			(effects
				(font
					(size 1.27 1.27)
					(thickness 0.15)
				)
				(justify left bottom)
				(hide yes)
			)
		)
		(property "Footprint" "antmicro-footprints:TE_2309413"
			(at 130.81 49.53 0)
			(effects
				(font
					(size 1.27 1.27)
					(thickness 0.15)
				)
				(justify left bottom)
				(hide yes)
			)
		)
		(property "Datasheet" "https://developer.nvidia.com/jetson-orin-nx-series-data-sheet"
			(at 130.81 52.07 0)
			(effects
				(font
					(size 1.27 1.27)
					(thickness 0.15)
				)
				(justify left bottom)
				(hide yes)
			)
		)
		(property "Description" ""
			(at 193.04 39.37 0)
			(effects
				(font
					(size 1.27 1.27)
				)
				(hide yes)
			)
		)
		(property "Manufacturer" "TE Connectivity"
			(at 130.81 54.61 0)
			(effects
				(font
					(size 1.27 1.27)
					(thickness 0.15)
				)
				(justify left bottom)
				(hide yes)
			)
		)
		(property "MPN" "2309413-1"
			(at 173.355 33.02 0)
			(effects
				(font
					(size 1.27 1.27)
					(thickness 0.15)
				)
			)
		)
		(property "License" "Apache-2.0"
			(at 130.81 59.69 0)
			(effects
				(font
					(size 1.27 1.27)
					(thickness 0.15)
				)
				(justify left bottom)
				(hide yes)
			)
		)
		(property "Author" "Antmicro"
			(at 130.81 62.23 0)
			(effects
				(font
					(size 1.27 1.27)
					(thickness 0.15)
				)
				(justify left bottom)
				(hide yes)
			)
		)
		(pin "245"
		)
		(pin "227"
		)
		(pin "229"
		)
		(pin "158"
		)
		(pin "184"
		)
		(pin "186"
		)
		(pin "248"
		)
		(pin "25"
		)
		(pin "16"
		)
		(pin "250"
		)
		(pin "35"
		)
		(pin "142"
		)
		(pin "148"
		)
		(pin "133"
		)
		(pin "134"
		)
		(pin "77"
		)
		(pin "81"
		)
		(pin "136"
		)
		(pin "137"
		)
		(pin "207"
		)
		(pin "168"
		)
		(pin "39"
		)
		(pin "36"
		)
		(pin "65"
		)
		(pin "69"
		)
		(pin "21"
		)
		(pin "209"
		)
		(pin "139"
		)
		(pin "140"
		)
		(pin "205"
		)
		(pin "182"
		)
		(pin "183"
		)
		(pin "107"
		)
		(pin "72"
		)
		(pin "84"
		)
		(pin "212"
		)
		(pin "216"
		)
		(pin "114"
		)
		(pin "50"
		)
		(pin "199"
		)
		(pin "68"
		)
		(pin "37"
		)
		(pin "31"
		)
		(pin "74"
		)
		(pin "252"
		)
		(pin "7"
		)
		(pin "197"
		)
		(pin "53"
		)
		(pin "57"
		)
		(pin "202"
		)
		(pin "204"
		)
		(pin "261"
		)
		(pin "100"
		)
		(pin "63"
		)
		(pin "15"
		)
		(pin "17"
		)
		(pin "6"
		)
		(pin "201"
		)
		(pin "169"
		)
		(pin "172"
		)
		(pin "4"
		)
		(pin "2"
		)
		(pin "159"
		)
		(pin "43"
		)
		(pin "70"
		)
		(pin "141"
		)
		(pin "3"
		)
		(pin "29"
		)
		(pin "233"
		)
		(pin "164"
		)
		(pin "147"
		)
		(pin "10"
		)
		(pin "219"
		)
		(pin "221"
		)
		(pin "40"
		)
		(pin "42"
		)
		(pin "223"
		)
		(pin "225"
		)
		(pin "120"
		)
		(pin "122"
		)
		(pin "73"
		)
		(pin "117"
		)
		(pin "121"
		)
		(pin "12"
		)
		(pin "83"
		)
		(pin "88"
		)
		(pin "99"
		)
		(pin "109"
		)
		(pin "64"
		)
		(pin "66"
		)
		(pin "188"
		)
		(pin "190"
		)
		(pin "192"
		)
		(pin "194"
		)
		(pin "59"
		)
		(pin "87"
		)
		(pin "251"
		)
		(pin "90"
		)
		(pin "92"
		)
		(pin "71"
		)
		(pin "75"
		)
		(pin "119"
		)
		(pin "126"
		)
		(pin "127"
		)
		(pin "1"
		)
		(pin "102"
		)
		(pin "52"
		)
		(pin "54"
		)
		(pin "19"
		)
		(pin "253"
		)
		(pin "260"
		)
		(pin "230"
		)
		(pin "151"
		)
		(pin "154"
		)
		(pin "247"
		)
		(pin "67"
		)
		(pin "243"
		)
		(pin "155"
		)
		(pin "156"
		)
		(pin "20"
		)
		(pin "208"
		)
		(pin "242"
		)
		(pin "231"
		)
		(pin "14"
		)
		(pin "241"
		)
		(pin "78"
		)
		(pin "132"
		)
		(pin "18"
		)
		(pin "240"
		)
		(pin "171"
		)
		(pin "170"
		)
		(pin "153"
		)
		(pin "49"
		)
		(pin "178"
		)
		(pin "226"
		)
		(pin "232"
		)
		(pin "176"
		)
		(pin "185"
		)
		(pin "9"
		)
		(pin "152"
		)
		(pin "101"
		)
		(pin "143"
		)
		(pin "165"
		)
		(pin "257"
		)
		(pin "103"
		)
		(pin "85"
		)
		(pin "259"
		)
		(pin "104"
		)
		(pin "146"
		)
		(pin "220"
		)
		(pin "246"
		)
		(pin "180"
		)
		(pin "181"
		)
		(pin "105"
		)
		(pin "210"
		)
		(pin "254"
		)
		(pin "256"
		)
		(pin "118"
		)
		(pin "124"
		)
		(pin "217"
		)
		(pin "214"
		)
		(pin "255"
		)
		(pin "30"
		)
		(pin "111"
		)
		(pin "115"
		)
		(pin "258"
		)
		(pin "213"
		)
		(pin "82"
		)
		(pin "129"
		)
		(pin "144"
		)
		(pin "128"
		)
		(pin "130"
		)
		(pin "61"
		)
		(pin "79"
		)
		(pin "26"
		)
		(pin "215"
		)
		(pin "33"
		)
		(pin "13"
		)
		(pin "22"
		)
		(pin "62"
		)
		(pin "113"
		)
		(pin "187"
		)
		(pin "177"
		)
		(pin "125"
		)
		(pin "80"
		)
		(pin "8"
		)
		(pin "234"
		)
		(pin "236"
		)
		(pin "238"
		)
		(pin "89"
		)
		(pin "91"
		)
		(pin "93"
		)
		(pin "95"
		)
		(pin "97"
		)
		(pin "222"
		)
		(pin "224"
		)
		(pin "44"
		)
		(pin "135"
		)
		(pin "206"
		)
		(pin "211"
		)
		(pin "86"
		)
		(pin "108"
		)
		(pin "34"
		)
		(pin "218"
		)
		(pin "228"
		)
		(pin "47"
		)
		(pin "51"
		)
		(pin "262"
		)
		(pin "11"
		)
		(pin "203"
		)
		(pin "41"
		)
		(pin "45"
		)
		(pin "123"
		)
		(pin "161"
		)
		(pin "173"
		)
		(pin "174"
		)
		(pin "23"
		)
		(pin "24"
		)
		(pin "55"
		)
		(pin "28"
		)
		(pin "191"
		)
		(pin "27"
		)
		(pin "46"
		)
		(pin "48"
		)
		(pin "163"
		)
		(pin "166"
		)
		(pin "193"
		)
		(pin "195"
		)
		(pin "235"
		)
		(pin "110"
		)
		(pin "237"
		)
		(pin "58"
		)
		(pin "60"
		)
		(pin "175"
		)
		(pin "179"
		)
		(pin "162"
		)
		(pin "167"
		)
		(pin "145"
		)
		(pin "249"
		)
		(pin "157"
		)
		(pin "160"
		)
		(pin "189"
		)
		(pin "239"
		)
		(pin "38"
		)
		(pin "112"
		)
		(pin "5"
		)
		(pin "106"
		)
		(pin "244"
		)
		(pin "149"
		)
		(pin "150"
		)
		(pin "76"
		)
		(pin "94"
		)
		(pin "96"
		)
		(pin "196"
		)
		(pin "198"
		)
		(pin "98"
		)
		(pin "131"
		)
		(pin "116"
		)
		(pin "138"
		)
		(pin "32"
		)
		(pin "200"
		)
		(pin "56"
		)
		(instances
			(project "jetson-orin-baseboard"
				(path ""
					(reference "J15")
					(unit 3)
				)
			)
		)
	)
	(symbol
		(lib_name "GND_7")
		(lib_id "antmicropower:GND")
		(at 54.61 165.1 0)
		(mirror y)
		(unit 1)
		(exclude_from_sim no)
		(in_bom yes)
		(on_board yes)
		(dnp no)
		(property "Reference" "#PWR012"
			(at 54.61 171.45 0)
			(effects
				(font
					(size 1.27 1.27)
				)
				(justify left bottom)
				(hide yes)
			)
		)
		(property "Value" "GND"
			(at 54.61 168.91 0)
			(effects
				(font
					(size 1.27 1.27)
					(thickness 0.15)
				)
			)
		)
		(property "Footprint" ""
			(at 45.72 172.72 0)
			(effects
				(font
					(size 1.27 1.27)
					(thickness 0.15)
				)
				(justify left bottom)
				(hide yes)
			)
		)
		(property "Datasheet" ""
			(at 45.72 177.8 0)
			(effects
				(font
					(size 1.27 1.27)
					(thickness 0.15)
				)
				(justify left bottom)
				(hide yes)
			)
		)
		(property "Description" ""
			(at 54.61 165.1 0)
			(effects
				(font
					(size 1.27 1.27)
				)
				(hide yes)
			)
		)
		(property "Author" "Antmicro"
			(at 45.72 172.72 0)
			(effects
				(font
					(size 1.27 1.27)
					(thickness 0.15)
				)
				(justify left bottom)
				(hide yes)
			)
		)
		(property "License" "Apache-2.0"
			(at 45.72 175.26 0)
			(effects
				(font
					(size 1.27 1.27)
					(thickness 0.15)
				)
				(justify left bottom)
				(hide yes)
			)
		)
		(pin "1"
		)
		(instances
			(project "jetson-orin-baseboard"
				(path ""
					(reference "#PWR012")
					(unit 1)
				)
			)
		)
	)
	(symbol
		(lib_id "antmicroResistors0402:R_0R_0402")
		(at 281.94 111.76 0)
		(unit 1)
		(exclude_from_sim no)
		(in_bom yes)
		(on_board yes)
		(dnp no)
		(property "Reference" "R11"
			(at 287.02 111.125 0)
			(effects
				(font
					(size 1.27 1.27)
				)
				(justify left bottom)
			)
		)
		(property "Value" "R_0R_0402"
			(at 302.26 124.46 0)
			(effects
				(font
					(size 1.27 1.27)
					(thickness 0.15)
				)
				(justify left bottom)
				(hide yes)
			)
		)
		(property "Footprint" "antmicro-footprints:R_0402_1005Metric"
			(at 302.26 127 0)
			(effects
				(font
					(size 1.27 1.27)
					(thickness 0.15)
				)
				(justify left bottom)
				(hide yes)
			)
		)
		(property "Datasheet" "https://industrial.panasonic.com/cdbs/www-data/pdf/RDA0000/AOA0000C301.pdf"
			(at 302.26 129.54 0)
			(effects
				(font
					(size 1.27 1.27)
					(thickness 0.15)
				)
				(justify left bottom)
				(hide yes)
			)
		)
		(property "Description" ""
			(at 281.94 111.76 0)
			(effects
				(font
					(size 1.27 1.27)
				)
				(hide yes)
			)
		)
		(property "Manufacturer" "Panasonic"
			(at 302.26 134.62 0)
			(effects
				(font
					(size 1.27 1.27)
					(thickness 0.15)
				)
				(justify left bottom)
				(hide yes)
			)
		)
		(property "MPN" "ERJ2GE0R00X"
			(at 302.26 132.08 0)
			(effects
				(font
					(size 1.27 1.27)
					(thickness 0.15)
				)
				(justify left bottom)
				(hide yes)
			)
		)
		(property "Val" "0R"
			(at 279.4 111.125 0)
			(effects
				(font
					(size 1.27 1.27)
					(thickness 0.15)
				)
				(justify left bottom)
			)
		)
		(property "License" "Apache-2.0"
			(at 302.26 137.16 0)
			(effects
				(font
					(size 1.27 1.27)
					(thickness 0.15)
				)
				(justify left bottom)
				(hide yes)
			)
		)
		(property "Author" "Antmicro"
			(at 302.26 139.7 0)
			(effects
				(font
					(size 1.27 1.27)
					(thickness 0.15)
				)
				(justify left bottom)
				(hide yes)
			)
		)
		(property "Tolerance" "~"
			(at 302.26 121.92 0)
			(effects
				(font
					(size 1.27 1.27)
				)
				(justify left bottom)
				(hide yes)
			)
		)
		(property "Current" "1A"
			(at 302.26 142.24 0)
			(effects
				(font
					(size 1.27 1.27)
					(thickness 0.15)
				)
				(justify left bottom)
				(hide yes)
			)
		)
		(pin "1"
		)
		(pin "2"
		)
		(instances
			(project "jetson-orin-baseboard"
				(path ""
					(reference "R11")
					(unit 1)
				)
			)
		)
	)
	(symbol
		(lib_name "TP_0.75mm_SMD_2")
		(lib_id "antmicroTestPoints:TP_0.75mm_SMD")
		(at 105.41 160.02 0)
		(unit 1)
		(exclude_from_sim no)
		(in_bom no)
		(on_board yes)
		(dnp no)
		(property "Reference" "TP44"
			(at 109.22 160.02 0)
			(effects
				(font
					(size 1.27 1.27)
				)
				(justify left)
			)
		)
		(property "Value" "TP_0.75mm_SMD"
			(at 115.57 163.83 0)
			(effects
				(font
					(size 1.27 1.27)
					(thickness 0.15)
				)
				(justify left bottom)
				(hide yes)
			)
		)
		(property "Footprint" "antmicro-footprints:TP_SMD_0.75mm"
			(at 115.57 166.37 0)
			(effects
				(font
					(size 1.27 1.27)
					(thickness 0.15)
				)
				(justify left bottom)
				(hide yes)
			)
		)
		(property "Datasheet" ""
			(at 123.19 172.72 0)
			(effects
				(font
					(size 1.27 1.27)
					(thickness 0.15)
				)
				(justify left bottom)
				(hide yes)
			)
		)
		(property "Description" ""
			(at 105.41 160.02 0)
			(effects
				(font
					(size 1.27 1.27)
				)
				(hide yes)
			)
		)
		(property "MPN" ""
			(at 116.205 171.45 0)
			(effects
				(font
					(size 1.27 1.27)
					(thickness 0.15)
				)
				(justify left bottom)
				(hide yes)
			)
		)
		(property "Manufacturer" ""
			(at 116.205 166.37 0)
			(effects
				(font
					(size 1.27 1.27)
					(thickness 0.15)
				)
				(justify left bottom)
				(hide yes)
			)
		)
		(property "Author" "Antmicro"
			(at 115.57 168.91 0)
			(effects
				(font
					(size 1.27 1.27)
					(thickness 0.15)
				)
				(justify left bottom)
				(hide yes)
			)
		)
		(property "License" "Apache-2.0"
			(at 115.57 171.45 0)
			(effects
				(font
					(size 1.27 1.27)
					(thickness 0.15)
				)
				(justify left bottom)
				(hide yes)
			)
		)
		(pin "1"
		)
		(instances
			(project "jetson-orin-baseboard"
				(path ""
					(reference "TP44")
					(unit 1)
				)
			)
		)
	)
	(symbol
		(lib_id "antmicroSoMConnectors:Bus_DDR4_SODIMM_CUSTOM_Jetson-Orin-H9.2mm-socket")
		(at 55.88 135.89 0)
		(unit 1)
		(exclude_from_sim no)
		(in_bom yes)
		(on_board yes)
		(dnp no)
		(fields_autoplaced yes)
		(property "Reference" "J15"
			(at 80.01 125.73 0)
			(effects
				(font
					(size 1.27 1.27)
					(thickness 0.15)
				)
			)
		)
		(property "Value" "Bus_DDR4_SODIMM_CUSTOM_Jetson-Orin-H9.2mm-socket"
			(at 118.11 143.51 0)
			(effects
				(font
					(size 1.27 1.27)
					(thickness 0.15)
				)
				(justify left bottom)
				(hide yes)
			)
		)
		(property "Footprint" "antmicro-footprints:TE_2309413"
			(at 118.11 146.05 0)
			(effects
				(font
					(size 1.27 1.27)
					(thickness 0.15)
				)
				(justify left bottom)
				(hide yes)
			)
		)
		(property "Datasheet" "https://developer.nvidia.com/jetson-orin-nx-series-data-sheet"
			(at 118.11 148.59 0)
			(effects
				(font
					(size 1.27 1.27)
					(thickness 0.15)
				)
				(justify left bottom)
				(hide yes)
			)
		)
		(property "Description" ""
			(at 55.88 135.89 0)
			(effects
				(font
					(size 1.27 1.27)
				)
				(hide yes)
			)
		)
		(property "Manufacturer" "TE Connectivity"
			(at 118.11 151.13 0)
			(effects
				(font
					(size 1.27 1.27)
					(thickness 0.15)
				)
				(justify left bottom)
				(hide yes)
			)
		)
		(property "MPN" "2309413-1"
			(at 80.01 128.27 0)
			(effects
				(font
					(size 1.27 1.27)
					(thickness 0.15)
				)
			)
		)
		(property "License" "Apache-2.0"
			(at 118.11 156.21 0)
			(effects
				(font
					(size 1.27 1.27)
					(thickness 0.15)
				)
				(justify left bottom)
				(hide yes)
			)
		)
		(property "Author" "Antmicro"
			(at 118.11 158.75 0)
			(effects
				(font
					(size 1.27 1.27)
					(thickness 0.15)
				)
				(justify left bottom)
				(hide yes)
			)
		)
		(pin "245"
		)
		(pin "227"
		)
		(pin "229"
		)
		(pin "158"
		)
		(pin "184"
		)
		(pin "186"
		)
		(pin "248"
		)
		(pin "25"
		)
		(pin "16"
		)
		(pin "250"
		)
		(pin "35"
		)
		(pin "142"
		)
		(pin "148"
		)
		(pin "133"
		)
		(pin "134"
		)
		(pin "77"
		)
		(pin "81"
		)
		(pin "136"
		)
		(pin "137"
		)
		(pin "207"
		)
		(pin "168"
		)
		(pin "39"
		)
		(pin "36"
		)
		(pin "65"
		)
		(pin "69"
		)
		(pin "21"
		)
		(pin "209"
		)
		(pin "139"
		)
		(pin "140"
		)
		(pin "205"
		)
		(pin "182"
		)
		(pin "183"
		)
		(pin "107"
		)
		(pin "72"
		)
		(pin "84"
		)
		(pin "212"
		)
		(pin "216"
		)
		(pin "114"
		)
		(pin "50"
		)
		(pin "199"
		)
		(pin "68"
		)
		(pin "37"
		)
		(pin "31"
		)
		(pin "74"
		)
		(pin "252"
		)
		(pin "7"
		)
		(pin "197"
		)
		(pin "53"
		)
		(pin "57"
		)
		(pin "202"
		)
		(pin "204"
		)
		(pin "261"
		)
		(pin "100"
		)
		(pin "63"
		)
		(pin "15"
		)
		(pin "17"
		)
		(pin "6"
		)
		(pin "201"
		)
		(pin "169"
		)
		(pin "172"
		)
		(pin "4"
		)
		(pin "2"
		)
		(pin "159"
		)
		(pin "43"
		)
		(pin "70"
		)
		(pin "141"
		)
		(pin "3"
		)
		(pin "29"
		)
		(pin "233"
		)
		(pin "164"
		)
		(pin "147"
		)
		(pin "10"
		)
		(pin "219"
		)
		(pin "221"
		)
		(pin "40"
		)
		(pin "42"
		)
		(pin "223"
		)
		(pin "225"
		)
		(pin "120"
		)
		(pin "122"
		)
		(pin "73"
		)
		(pin "117"
		)
		(pin "121"
		)
		(pin "12"
		)
		(pin "83"
		)
		(pin "88"
		)
		(pin "99"
		)
		(pin "109"
		)
		(pin "64"
		)
		(pin "66"
		)
		(pin "188"
		)
		(pin "190"
		)
		(pin "192"
		)
		(pin "194"
		)
		(pin "59"
		)
		(pin "87"
		)
		(pin "251"
		)
		(pin "90"
		)
		(pin "92"
		)
		(pin "71"
		)
		(pin "75"
		)
		(pin "119"
		)
		(pin "126"
		)
		(pin "127"
		)
		(pin "1"
		)
		(pin "102"
		)
		(pin "52"
		)
		(pin "54"
		)
		(pin "19"
		)
		(pin "253"
		)
		(pin "260"
		)
		(pin "230"
		)
		(pin "151"
		)
		(pin "154"
		)
		(pin "247"
		)
		(pin "67"
		)
		(pin "243"
		)
		(pin "155"
		)
		(pin "156"
		)
		(pin "20"
		)
		(pin "208"
		)
		(pin "242"
		)
		(pin "231"
		)
		(pin "14"
		)
		(pin "241"
		)
		(pin "78"
		)
		(pin "132"
		)
		(pin "18"
		)
		(pin "240"
		)
		(pin "171"
		)
		(pin "170"
		)
		(pin "153"
		)
		(pin "49"
		)
		(pin "178"
		)
		(pin "226"
		)
		(pin "232"
		)
		(pin "176"
		)
		(pin "185"
		)
		(pin "9"
		)
		(pin "152"
		)
		(pin "101"
		)
		(pin "143"
		)
		(pin "165"
		)
		(pin "257"
		)
		(pin "103"
		)
		(pin "85"
		)
		(pin "259"
		)
		(pin "104"
		)
		(pin "146"
		)
		(pin "220"
		)
		(pin "246"
		)
		(pin "180"
		)
		(pin "181"
		)
		(pin "105"
		)
		(pin "210"
		)
		(pin "254"
		)
		(pin "256"
		)
		(pin "118"
		)
		(pin "124"
		)
		(pin "217"
		)
		(pin "214"
		)
		(pin "255"
		)
		(pin "30"
		)
		(pin "111"
		)
		(pin "115"
		)
		(pin "258"
		)
		(pin "213"
		)
		(pin "82"
		)
		(pin "129"
		)
		(pin "144"
		)
		(pin "128"
		)
		(pin "130"
		)
		(pin "61"
		)
		(pin "79"
		)
		(pin "26"
		)
		(pin "215"
		)
		(pin "33"
		)
		(pin "13"
		)
		(pin "22"
		)
		(pin "62"
		)
		(pin "113"
		)
		(pin "187"
		)
		(pin "177"
		)
		(pin "125"
		)
		(pin "80"
		)
		(pin "8"
		)
		(pin "234"
		)
		(pin "236"
		)
		(pin "238"
		)
		(pin "89"
		)
		(pin "91"
		)
		(pin "93"
		)
		(pin "95"
		)
		(pin "97"
		)
		(pin "222"
		)
		(pin "224"
		)
		(pin "44"
		)
		(pin "135"
		)
		(pin "206"
		)
		(pin "211"
		)
		(pin "86"
		)
		(pin "108"
		)
		(pin "34"
		)
		(pin "218"
		)
		(pin "228"
		)
		(pin "47"
		)
		(pin "51"
		)
		(pin "262"
		)
		(pin "11"
		)
		(pin "203"
		)
		(pin "41"
		)
		(pin "45"
		)
		(pin "123"
		)
		(pin "161"
		)
		(pin "173"
		)
		(pin "174"
		)
		(pin "23"
		)
		(pin "24"
		)
		(pin "55"
		)
		(pin "28"
		)
		(pin "191"
		)
		(pin "27"
		)
		(pin "46"
		)
		(pin "48"
		)
		(pin "163"
		)
		(pin "166"
		)
		(pin "193"
		)
		(pin "195"
		)
		(pin "235"
		)
		(pin "110"
		)
		(pin "237"
		)
		(pin "58"
		)
		(pin "60"
		)
		(pin "175"
		)
		(pin "179"
		)
		(pin "162"
		)
		(pin "167"
		)
		(pin "145"
		)
		(pin "249"
		)
		(pin "157"
		)
		(pin "160"
		)
		(pin "189"
		)
		(pin "239"
		)
		(pin "38"
		)
		(pin "112"
		)
		(pin "5"
		)
		(pin "106"
		)
		(pin "244"
		)
		(pin "149"
		)
		(pin "150"
		)
		(pin "76"
		)
		(pin "94"
		)
		(pin "96"
		)
		(pin "196"
		)
		(pin "198"
		)
		(pin "98"
		)
		(pin "131"
		)
		(pin "116"
		)
		(pin "138"
		)
		(pin "32"
		)
		(pin "200"
		)
		(pin "56"
		)
		(instances
			(project "jetson-orin-baseboard"
				(path ""
					(reference "J15")
					(unit 1)
				)
			)
		)
	)
	(symbol
		(lib_name "GND_1")
		(lib_id "antmicropower:GND")
		(at 113.03 177.8 0)
		(unit 1)
		(exclude_from_sim no)
		(in_bom yes)
		(on_board yes)
		(dnp no)
		(property "Reference" "#PWR017"
			(at 113.03 184.15 0)
			(effects
				(font
					(size 1.27 1.27)
				)
				(justify left bottom)
				(hide yes)
			)
		)
		(property "Value" "GND"
			(at 113.03 181.61 0)
			(effects
				(font
					(size 1.27 1.27)
					(thickness 0.15)
				)
			)
		)
		(property "Footprint" ""
			(at 121.92 185.42 0)
			(effects
				(font
					(size 1.27 1.27)
					(thickness 0.15)
				)
				(justify left bottom)
				(hide yes)
			)
		)
		(property "Datasheet" ""
			(at 121.92 190.5 0)
			(effects
				(font
					(size 1.27 1.27)
					(thickness 0.15)
				)
				(justify left bottom)
				(hide yes)
			)
		)
		(property "Description" ""
			(at 113.03 177.8 0)
			(effects
				(font
					(size 1.27 1.27)
				)
				(hide yes)
			)
		)
		(property "Author" "Antmicro"
			(at 121.92 185.42 0)
			(effects
				(font
					(size 1.27 1.27)
					(thickness 0.15)
				)
				(justify left bottom)
				(hide yes)
			)
		)
		(property "License" "Apache-2.0"
			(at 121.92 187.96 0)
			(effects
				(font
					(size 1.27 1.27)
					(thickness 0.15)
				)
				(justify left bottom)
				(hide yes)
			)
		)
		(pin "1"
		)
		(instances
			(project "jetson-orin-baseboard"
				(path ""
					(reference "#PWR017")
					(unit 1)
				)
			)
		)
	)
)
